<HTML>
<HEAD>
<TITLE>BOMHDL Report BOM_20210112_PDM_3.html</TITLE>
<META NAME="Product Name" CONTENT="Bomhdl">
<META NAME="Product Version" CONTENT="17.2-2016 S075 (3923560)">
<META NAME="Product Date" CONTENT="3/10/2021">
</HEAD>
<BODY>
<P>&nbsp;</P>
<TABLE BORDER=0 CELLSPACING=0 CELLPADING=8 WIDTH=576>
<TR>
<TD WIDTH="27%" VALIGN="Top" ALIGN="Left">
<B><P>TITLE</B>
</TD>
<TD WIDTH="72%" VALIGN="Top" ALIGN="Left">
<P>Bill of Materials
</TD>
</TR>
<TR>
<TD WIDTH="27%" VALIGN="Top" ALIGN="Left">
<B><P>DATE</B>
</TD>
<TD WIDTH="72%" VALIGN="Top" ALIGN="Left">
<P>12/01/2021
</TD>
</TR>
<TR>
<TD WIDTH="27%" VALIGN="Top" ALIGN="Left">
<B><P>DESIGN</B>
</TD>
<TD WIDTH="72%" VALIGN="Top" ALIGN="Left">
<P>scm
</TD>
</TR>
<TR>
<TD WIDTH="27%" VALIGN="Top" ALIGN="Left">
<B><P>TEMPLATE</B>
</TD>
<TD WIDTH="72%" VALIGN="Top" ALIGN="Left">
<P>c:\cadence\spb_17.2\share\cdssetup\template.bom
</TD>
</TR>
<TR>
<TD WIDTH="27%" VALIGN="Top" ALIGN="Left">
<B><P>CALLOUT</B>
</TD>
<TD WIDTH="72%" VALIGN="Top" ALIGN="Left">
</TD>
</TR>
</TABLE>
<P>&nbsp;</P><TABLE BORDER=1 CELLSPACING=0 CELLPADING=8 WIDTH=880>
<TR>
<TD WIDTH="5%" VALIGN="Top" ALIGN="Right">
<B><P>S.No.</B>
</TD>
<TD WIDTH="9%" VALIGN="Top" ALIGN="Left">
<B><P>PART_NUMBE</B>
<B><P>R</B>
</TD>
<TD WIDTH="9%" VALIGN="Top" ALIGN="Left">
<B><P>DESCRIPTIO</B>
<B><P>N</B>
</TD>
<TD WIDTH="9%" VALIGN="Top" ALIGN="Left">
<B><P>MATERIAL</B>
</TD>
<TD WIDTH="3%" VALIGN="Top" ALIGN="Right">
<B><P>Qty</B>
</TD>
<TD WIDTH="9%" VALIGN="Top" ALIGN="Left">
<B><P>MANUFTR</B>
</TD>
<TD WIDTH="9%" VALIGN="Top" ALIGN="Left">
<B><P>MANUF_PN</B>
</TD>
<TD WIDTH="18%" VALIGN="Top" ALIGN="Left">
<B><P>Ref Des</B>
</TD>
<TD WIDTH="9%" VALIGN="Top" ALIGN="Left">
<B><P>QPN</B>
</TD>
<TD WIDTH="9%" VALIGN="Top" ALIGN="Left">
<B><P>LIFECYCLE</B>
</TD>
<TD WIDTH="9%" VALIGN="Top" ALIGN="Left">
<B><P>STANDARD</B>
</TD>
</TR>
<TR>
<TD WIDTH="5%" VALIGN="Top" ALIGN="Right">
<P>0
</TD>
<TD WIDTH="9%" VALIGN="Top" ALIGN="Left">
<P>AJ021000T0
<P>3
</TD>
<TD WIDTH="9%" VALIGN="Top" ALIGN="Left">
<P>ICOTHER(25
<P>6P)LCMXO3L
<P>F-2100C-5B
<P>G256(CABGA
</TD>
<TD WIDTH="9%" VALIGN="Top" ALIGN="Left">
<P>IC
</TD>
<TD WIDTH="3%" VALIGN="Top" ALIGN="Right">
<P>1
</TD>
<TD WIDTH="9%" VALIGN="Top" ALIGN="Left">
<P>LSC
</TD>
<TD WIDTH="9%" VALIGN="Top" ALIGN="Left">
<P>LCMXO3LF-2
<P>100C-5BG25
<P>6C
</TD>
<TD WIDTH="18%" VALIGN="Top" ALIGN="Left">
<P>U25
</TD>
<TD WIDTH="9%" VALIGN="Top" ALIGN="Left">
<P>?
</TD>
<TD WIDTH="9%" VALIGN="Top" ALIGN="Left">
<P>?
</TD>
<TD WIDTH="9%" VALIGN="Top" ALIGN="Left">
<P>?
</TD>
</TR>
<TR>
<TD WIDTH="5%" VALIGN="Top" ALIGN="Right">
<P>1
</TD>
<TD WIDTH="9%" VALIGN="Top" ALIGN="Left">
<P>AJ026000T0
<P>6
</TD>
<TD WIDTH="9%" VALIGN="Top" ALIGN="Left">
<P>IC(624P)AS
<P>T2600A3-GP
<P>(TFBGA)
</TD>
<TD WIDTH="9%" VALIGN="Top" ALIGN="Left">
<P>IC
</TD>
<TD WIDTH="3%" VALIGN="Top" ALIGN="Right">
<P>1
</TD>
<TD WIDTH="9%" VALIGN="Top" ALIGN="Left">
<P>APD
</TD>
<TD WIDTH="9%" VALIGN="Top" ALIGN="Left">
<P>AST2600A3-
<P>GP
</TD>
<TD WIDTH="18%" VALIGN="Top" ALIGN="Left">
<P>U5
</TD>
<TD WIDTH="9%" VALIGN="Top" ALIGN="Left">
<P>?
</TD>
<TD WIDTH="9%" VALIGN="Top" ALIGN="Left">
<P>?
</TD>
<TD WIDTH="9%" VALIGN="Top" ALIGN="Left">
<P>?
</TD>
</TR>
<TR>
<TD WIDTH="5%" VALIGN="Top" ALIGN="Right">
<P>2
</TD>
<TD WIDTH="9%" VALIGN="Top" ALIGN="Left">
<P>AKD5FGUT50
<P>2
</TD>
<TD WIDTH="9%" VALIGN="Top" ALIGN="Left">
<P>IC 
<P>SDRAM(96P)
<P>K4A8G165WC
<P>-BCTD(FBGA
<P>)QBCON
</TD>
<TD WIDTH="9%" VALIGN="Top" ALIGN="Left">
<P>IC
</TD>
<TD WIDTH="3%" VALIGN="Top" ALIGN="Right">
<P>1
</TD>
<TD WIDTH="9%" VALIGN="Top" ALIGN="Left">
<P>SAM
</TD>
<TD WIDTH="9%" VALIGN="Top" ALIGN="Left">
<P>K4A8G165WC
<P>-BCTD
</TD>
<TD WIDTH="18%" VALIGN="Top" ALIGN="Left">
<P>U1
</TD>
<TD WIDTH="9%" VALIGN="Top" ALIGN="Left">
<P>?
</TD>
<TD WIDTH="9%" VALIGN="Top" ALIGN="Left">
<P>?
</TD>
<TD WIDTH="9%" VALIGN="Top" ALIGN="Left">
<P>?
</TD>
</TR>
<TR>
<TD WIDTH="5%" VALIGN="Top" ALIGN="Right">
<P>3
</TD>
<TD WIDTH="9%" VALIGN="Top" ALIGN="Left">
<P>AKE30Z0K61
<P>0
</TD>
<TD WIDTH="9%" VALIGN="Top" ALIGN="Left">
<P>IC(8P)M241
<P>28-BWDW6TP
<P>(TSSOP)
</TD>
<TD WIDTH="9%" VALIGN="Top" ALIGN="Left">
<P>IC
</TD>
<TD WIDTH="3%" VALIGN="Top" ALIGN="Right">
<P>1
</TD>
<TD WIDTH="9%" VALIGN="Top" ALIGN="Left">
<P>SGT
</TD>
<TD WIDTH="9%" VALIGN="Top" ALIGN="Left">
<P>M24128-BWD
<P>W6TP
</TD>
<TD WIDTH="18%" VALIGN="Top" ALIGN="Left">
<P>U19
</TD>
<TD WIDTH="9%" VALIGN="Top" ALIGN="Left">
<P>?
</TD>
<TD WIDTH="9%" VALIGN="Top" ALIGN="Left">
<P>?
</TD>
<TD WIDTH="9%" VALIGN="Top" ALIGN="Left">
<P>?
</TD>
</TR>
<TR>
<TD WIDTH="5%" VALIGN="Top" ALIGN="Right">
<P>4
</TD>
<TD WIDTH="9%" VALIGN="Top" ALIGN="Left">
<P>AKE3LF-0Z0
<P>0
</TD>
<TD WIDTH="9%" VALIGN="Top" ALIGN="Left">
<P>IC 
<P>FLASH(16P)
<P>MX66L1G45G
<P>MI-08G(SOP
<P>)
</TD>
<TD WIDTH="9%" VALIGN="Top" ALIGN="Left">
<P>IC
</TD>
<TD WIDTH="3%" VALIGN="Top" ALIGN="Right">
<P>2
</TD>
<TD WIDTH="9%" VALIGN="Top" ALIGN="Left">
<P>MAX
</TD>
<TD WIDTH="9%" VALIGN="Top" ALIGN="Left">
<P>MX66L1G45G
<P>MI-08G
</TD>
<TD WIDTH="18%" VALIGN="Top" ALIGN="Left">
<P>U7,U28
</TD>
<TD WIDTH="9%" VALIGN="Top" ALIGN="Left">
<P>?
</TD>
<TD WIDTH="9%" VALIGN="Top" ALIGN="Left">
<P>?
</TD>
<TD WIDTH="9%" VALIGN="Top" ALIGN="Left">
<P>?
</TD>
</TR>
<TR>
<TD WIDTH="5%" VALIGN="Top" ALIGN="Right">
<P>5
</TD>
<TD WIDTH="9%" VALIGN="Top" ALIGN="Left">
<P>AKE3QZPTL0
<P>2
</TD>
<TD WIDTH="9%" VALIGN="Top" ALIGN="Left">
<P>IC 
<P>FLASH(153P
<P>)MTFC8GAKA
<P>JCN-1M 
<P>WT(VFBGA)
</TD>
<TD WIDTH="9%" VALIGN="Top" ALIGN="Left">
<P>EMPTY
</TD>
<TD WIDTH="3%" VALIGN="Top" ALIGN="Right">
<P>1
</TD>
<TD WIDTH="9%" VALIGN="Top" ALIGN="Left">
<P>MTI
</TD>
<TD WIDTH="9%" VALIGN="Top" ALIGN="Left">
<P>MTFC8GAKAJ
<P>CN-1M WT
</TD>
<TD WIDTH="18%" VALIGN="Top" ALIGN="Left">
<P>U20
</TD>
<TD WIDTH="9%" VALIGN="Top" ALIGN="Left">
<P>?
</TD>
<TD WIDTH="9%" VALIGN="Top" ALIGN="Left">
<P>?
</TD>
<TD WIDTH="9%" VALIGN="Top" ALIGN="Left">
<P>?
</TD>
</TR>
<TR>
<TD WIDTH="5%" VALIGN="Top" ALIGN="Right">
<P>6
</TD>
<TD WIDTH="9%" VALIGN="Top" ALIGN="Left">
<P>AL000257K0
<P>0
</TD>
<TD WIDTH="9%" VALIGN="Top" ALIGN="Left">
<P>IC 
<P>OTHER(16P)
<P>IDTQS3VH25
<P>7PAG(TSSOP
<P>)
</TD>
<TD WIDTH="9%" VALIGN="Top" ALIGN="Left">
<P>IC
</TD>
<TD WIDTH="3%" VALIGN="Top" ALIGN="Right">
<P>2
</TD>
<TD WIDTH="9%" VALIGN="Top" ALIGN="Left">
<P>?
</TD>
<TD WIDTH="9%" VALIGN="Top" ALIGN="Left">
<P>IDTQS3VH25
<P>7PAG
</TD>
<TD WIDTH="18%" VALIGN="Top" ALIGN="Left">
<P>U21,U30
</TD>
<TD WIDTH="9%" VALIGN="Top" ALIGN="Left">
<P>?
</TD>
<TD WIDTH="9%" VALIGN="Top" ALIGN="Left">
<P>?
</TD>
<TD WIDTH="9%" VALIGN="Top" ALIGN="Left">
<P>?
</TD>
</TR>
<TR>
<TD WIDTH="5%" VALIGN="Top" ALIGN="Right">
<P>7
</TD>
<TD WIDTH="9%" VALIGN="Top" ALIGN="Left">
<P>AL000380K0
<P>0
</TD>
<TD WIDTH="9%" VALIGN="Top" ALIGN="Left">
<P>IC 
<P>OTHER(6P)N
<P>CP380HSNAJ
<P>AAT1G(TSOP
<P>-6)
</TD>
<TD WIDTH="9%" VALIGN="Top" ALIGN="Left">
<P>IC
</TD>
<TD WIDTH="3%" VALIGN="Top" ALIGN="Right">
<P>1
</TD>
<TD WIDTH="9%" VALIGN="Top" ALIGN="Left">
<P>ONS
</TD>
<TD WIDTH="9%" VALIGN="Top" ALIGN="Left">
<P>NCP380HSNA
<P>JAAT1G
</TD>
<TD WIDTH="18%" VALIGN="Top" ALIGN="Left">
<P>U10
</TD>
<TD WIDTH="9%" VALIGN="Top" ALIGN="Left">
<P>?
</TD>
<TD WIDTH="9%" VALIGN="Top" ALIGN="Left">
<P>?
</TD>
<TD WIDTH="9%" VALIGN="Top" ALIGN="Left">
<P>?
</TD>
</TR>
<TR>
<TD WIDTH="5%" VALIGN="Top" ALIGN="Right">
<P>8
</TD>
<TD WIDTH="9%" VALIGN="Top" ALIGN="Left">
<P>AL00069500
<P>1
</TD>
<TD WIDTH="9%" VALIGN="Top" ALIGN="Left">
<P>IC 
<P>CTRL(13P)N
<P>B695GD-Z(Q
<P>FN-13)
</TD>
<TD WIDTH="9%" VALIGN="Top" ALIGN="Left">
<P>IC
</TD>
<TD WIDTH="3%" VALIGN="Top" ALIGN="Right">
<P>2
</TD>
<TD WIDTH="9%" VALIGN="Top" ALIGN="Left">
<P>MPS
</TD>
<TD WIDTH="9%" VALIGN="Top" ALIGN="Left">
<P>NB695GD-Z
</TD>
<TD WIDTH="18%" VALIGN="Top" ALIGN="Left">
<P>PU41,PU42
</TD>
<TD WIDTH="9%" VALIGN="Top" ALIGN="Left">
<P>?
</TD>
<TD WIDTH="9%" VALIGN="Top" ALIGN="Left">
<P>?
</TD>
<TD WIDTH="9%" VALIGN="Top" ALIGN="Left">
<P>?
</TD>
</TR>
<TR>
<TD WIDTH="5%" VALIGN="Top" ALIGN="Right">
<P>9
</TD>
<TD WIDTH="9%" VALIGN="Top" ALIGN="Left">
<P>AL001G0700
<P>3
</TD>
<TD WIDTH="9%" VALIGN="Top" ALIGN="Left">
<P>IC 
<P>OTHER(5P)M
<P>C74VHC1G07
<P>DFT2G(SOT-
<P>353)
</TD>
<TD WIDTH="9%" VALIGN="Top" ALIGN="Left">
<P>IC
</TD>
<TD WIDTH="3%" VALIGN="Top" ALIGN="Right">
<P>1
</TD>
<TD WIDTH="9%" VALIGN="Top" ALIGN="Left">
<P>ONS
</TD>
<TD WIDTH="9%" VALIGN="Top" ALIGN="Left">
<P>MC74VHC1G0
<P>7DFT2G
</TD>
<TD WIDTH="18%" VALIGN="Top" ALIGN="Left">
<P>U13
</TD>
<TD WIDTH="9%" VALIGN="Top" ALIGN="Left">
<P>?
</TD>
<TD WIDTH="9%" VALIGN="Top" ALIGN="Left">
<P>?
</TD>
<TD WIDTH="9%" VALIGN="Top" ALIGN="Left">
<P>?
</TD>
</TR>
<TR>
<TD WIDTH="5%" VALIGN="Top" ALIGN="Right">
<P>10
</TD>
<TD WIDTH="9%" VALIGN="Top" ALIGN="Left">
<P>AL001G3203
<P>1
</TD>
<TD WIDTH="9%" VALIGN="Top" ALIGN="Left">
<P>IC OTHER 
<P>(5P)MC74VH
<P>C1G32DTT1G
<P>(SOT-23)
</TD>
<TD WIDTH="9%" VALIGN="Top" ALIGN="Left">
<P>IC
</TD>
<TD WIDTH="3%" VALIGN="Top" ALIGN="Right">
<P>1
</TD>
<TD WIDTH="9%" VALIGN="Top" ALIGN="Left">
<P>ONS
</TD>
<TD WIDTH="9%" VALIGN="Top" ALIGN="Left">
<P>MC74VHC1G3
<P>2DTT1G
</TD>
<TD WIDTH="18%" VALIGN="Top" ALIGN="Left">
<P>U9
</TD>
<TD WIDTH="9%" VALIGN="Top" ALIGN="Left">
<P>?
</TD>
<TD WIDTH="9%" VALIGN="Top" ALIGN="Left">
<P>?
</TD>
<TD WIDTH="9%" VALIGN="Top" ALIGN="Left">
<P>?
</TD>
</TR>
<TR>
<TD WIDTH="5%" VALIGN="Top" ALIGN="Right">
<P>11
</TD>
<TD WIDTH="9%" VALIGN="Top" ALIGN="Left">
<P>AL002G0700
<P>3
</TD>
<TD WIDTH="9%" VALIGN="Top" ALIGN="Left">
<P>IC 
<P>OTHER(6P)7
<P>4LVC2G07DW
<P>-7(SOT-363
<P>)
</TD>
<TD WIDTH="9%" VALIGN="Top" ALIGN="Left">
<P>IC
</TD>
<TD WIDTH="3%" VALIGN="Top" ALIGN="Right">
<P>3
</TD>
<TD WIDTH="9%" VALIGN="Top" ALIGN="Left">
<P>DDS
</TD>
<TD WIDTH="9%" VALIGN="Top" ALIGN="Left">
<P>74LVC2G07D
<P>W-7
</TD>
<TD WIDTH="18%" VALIGN="Top" ALIGN="Left">
<P>U6,U24,U47
</TD>
<TD WIDTH="9%" VALIGN="Top" ALIGN="Left">
<P>?
</TD>
<TD WIDTH="9%" VALIGN="Top" ALIGN="Left">
<P>?
</TD>
<TD WIDTH="9%" VALIGN="Top" ALIGN="Left">
<P>?
</TD>
</TR>
<TR>
<TD WIDTH="5%" VALIGN="Top" ALIGN="Right">
<P>12
</TD>
<TD WIDTH="9%" VALIGN="Top" ALIGN="Left">
<P>AL00321200
<P>3
</TD>
<TD WIDTH="9%" VALIGN="Top" ALIGN="Left">
<P>IC 
<P>OTHER(20P)
<P> PI3PCIE32
<P>12ZBEX(QFN
<P>)
</TD>
<TD WIDTH="9%" VALIGN="Top" ALIGN="Left">
<P>IC
</TD>
<TD WIDTH="3%" VALIGN="Top" ALIGN="Right">
<P>1
</TD>
<TD WIDTH="9%" VALIGN="Top" ALIGN="Left">
<P>PIM
</TD>
<TD WIDTH="9%" VALIGN="Top" ALIGN="Left">
<P>PI3PCIE321
<P>2ZBEX
</TD>
<TD WIDTH="18%" VALIGN="Top" ALIGN="Left">
<P>U22
</TD>
<TD WIDTH="9%" VALIGN="Top" ALIGN="Left">
<P>?
</TD>
<TD WIDTH="9%" VALIGN="Top" ALIGN="Left">
<P>?
</TD>
<TD WIDTH="9%" VALIGN="Top" ALIGN="Left">
<P>?
</TD>
</TR>
<TR>
<TD WIDTH="5%" VALIGN="Top" ALIGN="Right">
<P>13
</TD>
<TD WIDTH="9%" VALIGN="Top" ALIGN="Left">
<P>AL00335700
<P>9
</TD>
<TD WIDTH="9%" VALIGN="Top" ALIGN="Left">
<P>IC 
<P>OTHER(8P)F
<P>SA3357K8X(
<P>US8)
</TD>
<TD WIDTH="9%" VALIGN="Top" ALIGN="Left">
<P>IC
</TD>
<TD WIDTH="3%" VALIGN="Top" ALIGN="Right">
<P>2
</TD>
<TD WIDTH="9%" VALIGN="Top" ALIGN="Left">
<P>FAC
</TD>
<TD WIDTH="9%" VALIGN="Top" ALIGN="Left">
<P>FSA3357K8X
</TD>
<TD WIDTH="18%" VALIGN="Top" ALIGN="Left">
<P>U2,U3
</TD>
<TD WIDTH="9%" VALIGN="Top" ALIGN="Left">
<P>?
</TD>
<TD WIDTH="9%" VALIGN="Top" ALIGN="Left">
<P>?
</TD>
<TD WIDTH="9%" VALIGN="Top" ALIGN="Left">
<P>?
</TD>
</TR>
<TR>
<TD WIDTH="5%" VALIGN="Top" ALIGN="Right">
<P>14
</TD>
<TD WIDTH="9%" VALIGN="Top" ALIGN="Left">
<P>AL00352600
<P>2
</TD>
<TD WIDTH="9%" VALIGN="Top" ALIGN="Left">
<P>IC 
<P>OTHER(8P) 
<P>APL3526QBI
<P>-TRG(TDFN)
</TD>
<TD WIDTH="9%" VALIGN="Top" ALIGN="Left">
<P>IC
</TD>
<TD WIDTH="3%" VALIGN="Top" ALIGN="Right">
<P>1
</TD>
<TD WIDTH="9%" VALIGN="Top" ALIGN="Left">
<P>ANC
</TD>
<TD WIDTH="9%" VALIGN="Top" ALIGN="Left">
<P>APL3526QBI
<P>-TRG
</TD>
<TD WIDTH="18%" VALIGN="Top" ALIGN="Left">
<P>U15
</TD>
<TD WIDTH="9%" VALIGN="Top" ALIGN="Left">
<P>?
</TD>
<TD WIDTH="9%" VALIGN="Top" ALIGN="Left">
<P>?
</TD>
<TD WIDTH="9%" VALIGN="Top" ALIGN="Left">
<P>?
</TD>
</TR>
<TR>
<TD WIDTH="5%" VALIGN="Top" ALIGN="Right">
<P>15
</TD>
<TD WIDTH="9%" VALIGN="Top" ALIGN="Left">
<P>AL0075BD00
<P>0
</TD>
<TD WIDTH="9%" VALIGN="Top" ALIGN="Left">
<P>IC OTHER 
<P>(8P) 
<P>LM75BD(SO8
<P>)
</TD>
<TD WIDTH="9%" VALIGN="Top" ALIGN="Left">
<P>IC
</TD>
<TD WIDTH="3%" VALIGN="Top" ALIGN="Right">
<P>1
</TD>
<TD WIDTH="9%" VALIGN="Top" ALIGN="Left">
<P>NXP
</TD>
<TD WIDTH="9%" VALIGN="Top" ALIGN="Left">
<P>LM75BD
</TD>
<TD WIDTH="18%" VALIGN="Top" ALIGN="Left">
<P>U4
</TD>
<TD WIDTH="9%" VALIGN="Top" ALIGN="Left">
<P>?
</TD>
<TD WIDTH="9%" VALIGN="Top" ALIGN="Left">
<P>?
</TD>
<TD WIDTH="9%" VALIGN="Top" ALIGN="Left">
<P>?
</TD>
</TR>
<TR>
<TD WIDTH="5%" VALIGN="Top" ALIGN="Right">
<P>16
</TD>
<TD WIDTH="9%" VALIGN="Top" ALIGN="Left">
<P>AL00862600
<P>0
</TD>
<TD WIDTH="9%" VALIGN="Top" ALIGN="Left">
<P>IC 
<P>CTRL(14P)M
<P>PQ8626GD-Z
<P>(QFN)
</TD>
<TD WIDTH="9%" VALIGN="Top" ALIGN="Left">
<P>IC
</TD>
<TD WIDTH="3%" VALIGN="Top" ALIGN="Right">
<P>1
</TD>
<TD WIDTH="9%" VALIGN="Top" ALIGN="Left">
<P>MPS
</TD>
<TD WIDTH="9%" VALIGN="Top" ALIGN="Left">
<P>MPQ8626GD-
<P>Z
</TD>
<TD WIDTH="18%" VALIGN="Top" ALIGN="Left">
<P>PU1
</TD>
<TD WIDTH="9%" VALIGN="Top" ALIGN="Left">
<P>?
</TD>
<TD WIDTH="9%" VALIGN="Top" ALIGN="Left">
<P>?
</TD>
<TD WIDTH="9%" VALIGN="Top" ALIGN="Left">
<P>?
</TD>
</TR>
<TR>
<TD WIDTH="5%" VALIGN="Top" ALIGN="Right">
<P>17
</TD>
<TD WIDTH="9%" VALIGN="Top" ALIGN="Left">
<P>AL00863300
<P>7
</TD>
<TD WIDTH="9%" VALIGN="Top" ALIGN="Left">
<P>IC 
<P>CTRL(21P)M
<P>PQ8633AGLE
<P>-C807-Z(QF
<P>N)
</TD>
<TD WIDTH="9%" VALIGN="Top" ALIGN="Left">
<P>IC
</TD>
<TD WIDTH="3%" VALIGN="Top" ALIGN="Right">
<P>1
</TD>
<TD WIDTH="9%" VALIGN="Top" ALIGN="Left">
<P>MPS
</TD>
<TD WIDTH="9%" VALIGN="Top" ALIGN="Left">
<P>MPQ8633AGL
<P>E-C807-Z
</TD>
<TD WIDTH="18%" VALIGN="Top" ALIGN="Left">
<P>PU38
</TD>
<TD WIDTH="9%" VALIGN="Top" ALIGN="Left">
<P>?
</TD>
<TD WIDTH="9%" VALIGN="Top" ALIGN="Left">
<P>?
</TD>
<TD WIDTH="9%" VALIGN="Top" ALIGN="Left">
<P>?
</TD>
</TR>
<TR>
<TD WIDTH="5%" VALIGN="Top" ALIGN="Right">
<P>18
</TD>
<TD WIDTH="9%" VALIGN="Top" ALIGN="Left">
<P>AL00905900
<P>0
</TD>
<TD WIDTH="9%" VALIGN="Top" ALIGN="Left">
<P>IC 
<P>OTHER(10P)
<P> RT9059GQW
<P>(WDFN)
</TD>
<TD WIDTH="9%" VALIGN="Top" ALIGN="Left">
<P>IC
</TD>
<TD WIDTH="3%" VALIGN="Top" ALIGN="Right">
<P>2
</TD>
<TD WIDTH="9%" VALIGN="Top" ALIGN="Left">
<P>RTK
</TD>
<TD WIDTH="9%" VALIGN="Top" ALIGN="Left">
<P>RT9059GQW
</TD>
<TD WIDTH="18%" VALIGN="Top" ALIGN="Left">
<P>PU39,PU40
</TD>
<TD WIDTH="9%" VALIGN="Top" ALIGN="Left">
<P>?
</TD>
<TD WIDTH="9%" VALIGN="Top" ALIGN="Left">
<P>?
</TD>
<TD WIDTH="9%" VALIGN="Top" ALIGN="Left">
<P>?
</TD>
</TR>
<TR>
<TD WIDTH="5%" VALIGN="Top" ALIGN="Right">
<P>19
</TD>
<TD WIDTH="9%" VALIGN="Top" ALIGN="Left">
<P>AL009517K0
<P>0
</TD>
<TD WIDTH="9%" VALIGN="Top" ALIGN="Left">
<P>IC OTHER 
<P>(8P) 
<P>PCA9517ADP
<P>(TSSOP8)
</TD>
<TD WIDTH="9%" VALIGN="Top" ALIGN="Left">
<P>IC
</TD>
<TD WIDTH="3%" VALIGN="Top" ALIGN="Right">
<P>1
</TD>
<TD WIDTH="9%" VALIGN="Top" ALIGN="Left">
<P>?
</TD>
<TD WIDTH="9%" VALIGN="Top" ALIGN="Left">
<P>?
</TD>
<TD WIDTH="18%" VALIGN="Top" ALIGN="Left">
<P>U37
</TD>
<TD WIDTH="9%" VALIGN="Top" ALIGN="Left">
<P>?
</TD>
<TD WIDTH="9%" VALIGN="Top" ALIGN="Left">
<P>?
</TD>
<TD WIDTH="9%" VALIGN="Top" ALIGN="Left">
<P>?
</TD>
</TR>
<TR>
<TD WIDTH="5%" VALIGN="Top" ALIGN="Right">
<P>20
</TD>
<TD WIDTH="9%" VALIGN="Top" ALIGN="Left">
<P>AL02281100
<P>0
</TD>
<TD WIDTH="9%" VALIGN="Top" ALIGN="Left">
<P>IC 
<P>OTHER(5P)A
<P>P22811AW5-
<P>7(SOT25)
</TD>
<TD WIDTH="9%" VALIGN="Top" ALIGN="Left">
<P>IC
</TD>
<TD WIDTH="3%" VALIGN="Top" ALIGN="Right">
<P>1
</TD>
<TD WIDTH="9%" VALIGN="Top" ALIGN="Left">
<P>DDS
</TD>
<TD WIDTH="9%" VALIGN="Top" ALIGN="Left">
<P>AP22811AW5
<P>-7
</TD>
<TD WIDTH="18%" VALIGN="Top" ALIGN="Left">
<P>U14
</TD>
<TD WIDTH="9%" VALIGN="Top" ALIGN="Left">
<P>?
</TD>
<TD WIDTH="9%" VALIGN="Top" ALIGN="Left">
<P>?
</TD>
<TD WIDTH="9%" VALIGN="Top" ALIGN="Left">
<P>?
</TD>
</TR>
<TR>
<TD WIDTH="5%" VALIGN="Top" ALIGN="Right">
<P>21
</TD>
<TD WIDTH="9%" VALIGN="Top" ALIGN="Left">
<P>AL1G000701
<P>6
</TD>
<TD WIDTH="9%" VALIGN="Top" ALIGN="Left">
<P>IC 
<P>OTHER(5P)S
<P>N74LVC1G07
<P>DCKR(SOT)
</TD>
<TD WIDTH="9%" VALIGN="Top" ALIGN="Left">
<P>EMPTY
</TD>
<TD WIDTH="3%" VALIGN="Top" ALIGN="Right">
<P>2
</TD>
<TD WIDTH="9%" VALIGN="Top" ALIGN="Left">
<P>TIC
</TD>
<TD WIDTH="9%" VALIGN="Top" ALIGN="Left">
<P>SN74LVC1G0
<P>7DCKR
</TD>
<TD WIDTH="18%" VALIGN="Top" ALIGN="Left">
<P>U44,U45
</TD>
<TD WIDTH="9%" VALIGN="Top" ALIGN="Left">
<P>?
</TD>
<TD WIDTH="9%" VALIGN="Top" ALIGN="Left">
<P>?
</TD>
<TD WIDTH="9%" VALIGN="Top" ALIGN="Left">
<P>?
</TD>
</TR>
<TR>
<TD WIDTH="5%" VALIGN="Top" ALIGN="Right">
<P>22
</TD>
<TD WIDTH="9%" VALIGN="Top" ALIGN="Left">
<P>AL1G0017K0
<P>1
</TD>
<TD WIDTH="9%" VALIGN="Top" ALIGN="Left">
<P>IC 
<P>OTHER(5P) 
<P>74LVC1G17G
<P>W(TSSOP)
</TD>
<TD WIDTH="9%" VALIGN="Top" ALIGN="Left">
<P>IC
</TD>
<TD WIDTH="3%" VALIGN="Top" ALIGN="Right">
<P>2
</TD>
<TD WIDTH="9%" VALIGN="Top" ALIGN="Left">
<P>NXP
</TD>
<TD WIDTH="9%" VALIGN="Top" ALIGN="Left">
<P>74LVC1G17G
<P>W
</TD>
<TD WIDTH="18%" VALIGN="Top" ALIGN="Left">
<P>U32,U46
</TD>
<TD WIDTH="9%" VALIGN="Top" ALIGN="Left">
<P>?
</TD>
<TD WIDTH="9%" VALIGN="Top" ALIGN="Left">
<P>?
</TD>
<TD WIDTH="9%" VALIGN="Top" ALIGN="Left">
<P>?
</TD>
</TR>
<TR>
<TD WIDTH="5%" VALIGN="Top" ALIGN="Right">
<P>23
</TD>
<TD WIDTH="9%" VALIGN="Top" ALIGN="Left">
<P>AL1G012600
<P>7
</TD>
<TD WIDTH="9%" VALIGN="Top" ALIGN="Left">
<P>IC(5P) 
<P>74HC1G126G
<P>W(SOT353)E
<P>P
</TD>
<TD WIDTH="9%" VALIGN="Top" ALIGN="Left">
<P>IC
</TD>
<TD WIDTH="3%" VALIGN="Top" ALIGN="Right">
<P>4
</TD>
<TD WIDTH="9%" VALIGN="Top" ALIGN="Left">
<P>PHI
</TD>
<TD WIDTH="9%" VALIGN="Top" ALIGN="Left">
<P>74HC1G126G
<P>W
</TD>
<TD WIDTH="18%" VALIGN="Top" ALIGN="Left">
<P>U26,U29,U33,U36
</TD>
<TD WIDTH="9%" VALIGN="Top" ALIGN="Left">
<P>?
</TD>
<TD WIDTH="9%" VALIGN="Top" ALIGN="Left">
<P>?
</TD>
<TD WIDTH="9%" VALIGN="Top" ALIGN="Left">
<P>?
</TD>
</TR>
<TR>
<TD WIDTH="5%" VALIGN="Top" ALIGN="Right">
<P>24
</TD>
<TD WIDTH="9%" VALIGN="Top" ALIGN="Left">
<P>AL1G012600
<P>9
</TD>
<TD WIDTH="9%" VALIGN="Top" ALIGN="Left">
<P>IC 
<P>OTHER(5P) 
<P>74LVC1G126
<P>SE-7 
<P>(SOT353)
</TD>
<TD WIDTH="9%" VALIGN="Top" ALIGN="Left">
<P>IC
</TD>
<TD WIDTH="3%" VALIGN="Top" ALIGN="Right">
<P>1
</TD>
<TD WIDTH="9%" VALIGN="Top" ALIGN="Left">
<P>DDS
</TD>
<TD WIDTH="9%" VALIGN="Top" ALIGN="Left">
<P>74LVC1G126
<P>SE-7
</TD>
<TD WIDTH="18%" VALIGN="Top" ALIGN="Left">
<P>U8
</TD>
<TD WIDTH="9%" VALIGN="Top" ALIGN="Left">
<P>?
</TD>
<TD WIDTH="9%" VALIGN="Top" ALIGN="Left">
<P>?
</TD>
<TD WIDTH="9%" VALIGN="Top" ALIGN="Left">
<P>?
</TD>
</TR>
<TR>
<TD WIDTH="5%" VALIGN="Top" ALIGN="Right">
<P>25
</TD>
<TD WIDTH="9%" VALIGN="Top" ALIGN="Left">
<P>AL308330K0
<P>0
</TD>
<TD WIDTH="9%" VALIGN="Top" ALIGN="Left">
<P>IC 
<P>OTHER(6P)N
<P>CP308SN330
<P>T1G(TSOP)
</TD>
<TD WIDTH="9%" VALIGN="Top" ALIGN="Left">
<P>IC
</TD>
<TD WIDTH="3%" VALIGN="Top" ALIGN="Right">
<P>1
</TD>
<TD WIDTH="9%" VALIGN="Top" ALIGN="Left">
<P>ONS
</TD>
<TD WIDTH="9%" VALIGN="Top" ALIGN="Left">
<P>NCP308SN33
<P>0T1G
</TD>
<TD WIDTH="18%" VALIGN="Top" ALIGN="Left">
<P>U43
</TD>
<TD WIDTH="9%" VALIGN="Top" ALIGN="Left">
<P>?
</TD>
<TD WIDTH="9%" VALIGN="Top" ALIGN="Left">
<P>?
</TD>
<TD WIDTH="9%" VALIGN="Top" ALIGN="Left">
<P>?
</TD>
</TR>
<TR>
<TD WIDTH="5%" VALIGN="Top" ALIGN="Right">
<P>26
</TD>
<TD WIDTH="9%" VALIGN="Top" ALIGN="Left">
<P>AL5V0U2X00
<P>0
</TD>
<TD WIDTH="9%" VALIGN="Top" ALIGN="Left">
<P>IC OTHER 
<P>(4P) 
<P>PRTR5V0U2X
<P> (SOT143B)
</TD>
<TD WIDTH="9%" VALIGN="Top" ALIGN="Left">
<P>IC
</TD>
<TD WIDTH="3%" VALIGN="Top" ALIGN="Right">
<P>1
</TD>
<TD WIDTH="9%" VALIGN="Top" ALIGN="Left">
<P>NXP
</TD>
<TD WIDTH="9%" VALIGN="Top" ALIGN="Left">
<P>PRTR5V0U2X
</TD>
<TD WIDTH="18%" VALIGN="Top" ALIGN="Left">
<P>U38
</TD>
<TD WIDTH="9%" VALIGN="Top" ALIGN="Left">
<P>?
</TD>
<TD WIDTH="9%" VALIGN="Top" ALIGN="Left">
<P>?
</TD>
<TD WIDTH="9%" VALIGN="Top" ALIGN="Left">
<P>?
</TD>
</TR>
<TR>
<TD WIDTH="5%" VALIGN="Top" ALIGN="Right">
<P>27
</TD>
<TD WIDTH="9%" VALIGN="Top" ALIGN="Left">
<P>ALSB315700
<P>0
</TD>
<TD WIDTH="9%" VALIGN="Top" ALIGN="Left">
<P>IC(6P) 
<P>NC7SB3157P
<P>6X(SC70-6)
</TD>
<TD WIDTH="9%" VALIGN="Top" ALIGN="Left">
<P>IC
</TD>
<TD WIDTH="3%" VALIGN="Top" ALIGN="Right">
<P>2
</TD>
<TD WIDTH="9%" VALIGN="Top" ALIGN="Left">
<P>?
</TD>
<TD WIDTH="9%" VALIGN="Top" ALIGN="Left">
<P>NC7SB3157P
<P>6X
</TD>
<TD WIDTH="18%" VALIGN="Top" ALIGN="Left">
<P>U50,U51
</TD>
<TD WIDTH="9%" VALIGN="Top" ALIGN="Left">
<P>?
</TD>
<TD WIDTH="9%" VALIGN="Top" ALIGN="Left">
<P>?
</TD>
<TD WIDTH="9%" VALIGN="Top" ALIGN="Left">
<P>?
</TD>
</TR>
<TR>
<TD WIDTH="5%" VALIGN="Top" ALIGN="Right">
<P>28
</TD>
<TD WIDTH="9%" VALIGN="Top" ALIGN="Left">
<P>ALVC1G0700
<P>1
</TD>
<TD WIDTH="9%" VALIGN="Top" ALIGN="Left">
<P>IC(5P)74LV
<P>C1G07W5-7(
<P>SOT25)
</TD>
<TD WIDTH="9%" VALIGN="Top" ALIGN="Left">
<P>IC
</TD>
<TD WIDTH="3%" VALIGN="Top" ALIGN="Right">
<P>1
</TD>
<TD WIDTH="9%" VALIGN="Top" ALIGN="Left">
<P>DDS
</TD>
<TD WIDTH="9%" VALIGN="Top" ALIGN="Left">
<P>74LVC1G07W
<P>5-7
</TD>
<TD WIDTH="18%" VALIGN="Top" ALIGN="Left">
<P>U23
</TD>
<TD WIDTH="9%" VALIGN="Top" ALIGN="Left">
<P>?
</TD>
<TD WIDTH="9%" VALIGN="Top" ALIGN="Left">
<P>?
</TD>
<TD WIDTH="9%" VALIGN="Top" ALIGN="Left">
<P>?
</TD>
</TR>
<TR>
<TD WIDTH="5%" VALIGN="Top" ALIGN="Right">
<P>29
</TD>
<TD WIDTH="9%" VALIGN="Top" ALIGN="Left">
<P>ALVC1G0700
<P>2
</TD>
<TD WIDTH="9%" VALIGN="Top" ALIGN="Left">
<P>IC(5P) 
<P>74LVC1G07G
<P>W(SOT353)
</TD>
<TD WIDTH="9%" VALIGN="Top" ALIGN="Left">
<P>IC
</TD>
<TD WIDTH="3%" VALIGN="Top" ALIGN="Right">
<P>1
</TD>
<TD WIDTH="9%" VALIGN="Top" ALIGN="Left">
<P>PHI
</TD>
<TD WIDTH="9%" VALIGN="Top" ALIGN="Left">
<P>74LVC1G07G
<P>W
</TD>
<TD WIDTH="18%" VALIGN="Top" ALIGN="Left">
<P>U31
</TD>
<TD WIDTH="9%" VALIGN="Top" ALIGN="Left">
<P>?
</TD>
<TD WIDTH="9%" VALIGN="Top" ALIGN="Left">
<P>?
</TD>
<TD WIDTH="9%" VALIGN="Top" ALIGN="Left">
<P>?
</TD>
</TR>
<TR>
<TD WIDTH="5%" VALIGN="Top" ALIGN="Right">
<P>30
</TD>
<TD WIDTH="9%" VALIGN="Top" ALIGN="Left">
<P>BA0390400H
<P>0
</TD>
<TD WIDTH="9%" VALIGN="Top" ALIGN="Left">
<P>TRANS SMD 
<P>MMBT3904-7
<P>-F(40V,
<P>200MA,8W)
</TD>
<TD WIDTH="9%" VALIGN="Top" ALIGN="Left">
<P>IC
</TD>
<TD WIDTH="3%" VALIGN="Top" ALIGN="Right">
<P>2
</TD>
<TD WIDTH="9%" VALIGN="Top" ALIGN="Left">
<P>DDS
</TD>
<TD WIDTH="9%" VALIGN="Top" ALIGN="Left">
<P>MMBT3904-7
<P>-F
</TD>
<TD WIDTH="18%" VALIGN="Top" ALIGN="Left">
<P>Q1,Q3
</TD>
<TD WIDTH="9%" VALIGN="Top" ALIGN="Left">
<P>?
</TD>
<TD WIDTH="9%" VALIGN="Top" ALIGN="Left">
<P>Comp-Appro
<P>ve
</TD>
<TD WIDTH="9%" VALIGN="Top" ALIGN="Left">
<P>End of 
<P>Design
</TD>
</TR>
<TR>
<TD WIDTH="5%" VALIGN="Top" ALIGN="Right">
<P>31
</TD>
<TD WIDTH="9%" VALIGN="Top" ALIGN="Left">
<P>BAM0123001
<P>4
</TD>
<TD WIDTH="9%" VALIGN="Top" ALIGN="Left">
<P>TRANS 
<P>MOSFET 
<P>BSS123-7-F
<P>(100V.170M
<P>A)
</TD>
<TD WIDTH="9%" VALIGN="Top" ALIGN="Left">
<P>IC
</TD>
<TD WIDTH="3%" VALIGN="Top" ALIGN="Right">
<P>1
</TD>
<TD WIDTH="9%" VALIGN="Top" ALIGN="Left">
<P>DDS
</TD>
<TD WIDTH="9%" VALIGN="Top" ALIGN="Left">
<P>BSS123-7-F
</TD>
<TD WIDTH="18%" VALIGN="Top" ALIGN="Left">
<P>Q7
</TD>
<TD WIDTH="9%" VALIGN="Top" ALIGN="Left">
<P>?
</TD>
<TD WIDTH="9%" VALIGN="Top" ALIGN="Left">
<P>?
</TD>
<TD WIDTH="9%" VALIGN="Top" ALIGN="Left">
<P>?
</TD>
</TR>
<TR>
<TD WIDTH="5%" VALIGN="Top" ALIGN="Right">
<P>32
</TD>
<TD WIDTH="9%" VALIGN="Top" ALIGN="Left">
<P>BAM138K000
<P>0
</TD>
<TD WIDTH="9%" VALIGN="Top" ALIGN="Left">
<P>TRANS MOS 
<P>BSS138K(50
<P>V,0.22A,
<P>0.35W)
</TD>
<TD WIDTH="9%" VALIGN="Top" ALIGN="Left">
<P>IC
</TD>
<TD WIDTH="3%" VALIGN="Top" ALIGN="Right">
<P>3
</TD>
<TD WIDTH="9%" VALIGN="Top" ALIGN="Left">
<P>?
</TD>
<TD WIDTH="9%" VALIGN="Top" ALIGN="Left">
<P>BSS138K
</TD>
<TD WIDTH="18%" VALIGN="Top" ALIGN="Left">
<P>Q21,Q22,U12
</TD>
<TD WIDTH="9%" VALIGN="Top" ALIGN="Left">
<P>?
</TD>
<TD WIDTH="9%" VALIGN="Top" ALIGN="Left">
<P>?
</TD>
<TD WIDTH="9%" VALIGN="Top" ALIGN="Left">
<P>?
</TD>
</TR>
<TR>
<TD WIDTH="5%" VALIGN="Top" ALIGN="Right">
<P>33
</TD>
<TD WIDTH="9%" VALIGN="Top" ALIGN="Left">
<P>BAM138K000
<P>3
</TD>
<TD WIDTH="9%" VALIGN="Top" ALIGN="Left">
<P>TRANS 
<P>MOSFET 
<P>PJT138K(50
<P>V,0.36A,
<P>0.236W)
</TD>
<TD WIDTH="9%" VALIGN="Top" ALIGN="Left">
<P>IC
</TD>
<TD WIDTH="3%" VALIGN="Top" ALIGN="Right">
<P>1
</TD>
<TD WIDTH="9%" VALIGN="Top" ALIGN="Left">
<P>PJT
</TD>
<TD WIDTH="9%" VALIGN="Top" ALIGN="Left">
<P>PJT138K
</TD>
<TD WIDTH="18%" VALIGN="Top" ALIGN="Left">
<P>Q9
</TD>
<TD WIDTH="9%" VALIGN="Top" ALIGN="Left">
<P>?
</TD>
<TD WIDTH="9%" VALIGN="Top" ALIGN="Left">
<P>?
</TD>
<TD WIDTH="9%" VALIGN="Top" ALIGN="Left">
<P>?
</TD>
</TR>
<TR>
<TD WIDTH="5%" VALIGN="Top" ALIGN="Right">
<P>34
</TD>
<TD WIDTH="9%" VALIGN="Top" ALIGN="Left">
<P>BAM2305002
<P>7
</TD>
<TD WIDTH="9%" VALIGN="Top" ALIGN="Left">
<P>TRAN 
<P>P-MOSFET 
<P>AP2305GN-2
<P>0V,
<P>1.38W(SOT-
<P>23)
</TD>
<TD WIDTH="9%" VALIGN="Top" ALIGN="Left">
<P>EMPTY
</TD>
<TD WIDTH="3%" VALIGN="Top" ALIGN="Right">
<P>1
</TD>
<TD WIDTH="9%" VALIGN="Top" ALIGN="Left">
<P>AVP
</TD>
<TD WIDTH="9%" VALIGN="Top" ALIGN="Left">
<P>AP2305GN
</TD>
<TD WIDTH="18%" VALIGN="Top" ALIGN="Left">
<P>Q4
</TD>
<TD WIDTH="9%" VALIGN="Top" ALIGN="Left">
<P>?
</TD>
<TD WIDTH="9%" VALIGN="Top" ALIGN="Left">
<P>?
</TD>
<TD WIDTH="9%" VALIGN="Top" ALIGN="Left">
<P>?
</TD>
</TR>
<TR>
<TD WIDTH="5%" VALIGN="Top" ALIGN="Right">
<P>35
</TD>
<TD WIDTH="9%" VALIGN="Top" ALIGN="Left">
<P>BAM4141000
<P>5
</TD>
<TD WIDTH="9%" VALIGN="Top" ALIGN="Left">
<P>TRANS MOS 
<P>NTGS4141NT
<P>1G(30V,
<P>7.0A,
<P>TSOP6)
</TD>
<TD WIDTH="9%" VALIGN="Top" ALIGN="Left">
<P>IC
</TD>
<TD WIDTH="3%" VALIGN="Top" ALIGN="Right">
<P>1
</TD>
<TD WIDTH="9%" VALIGN="Top" ALIGN="Left">
<P>ONS
</TD>
<TD WIDTH="9%" VALIGN="Top" ALIGN="Left">
<P>NTGS4141NT
<P>1G
</TD>
<TD WIDTH="18%" VALIGN="Top" ALIGN="Left">
<P>Q5
</TD>
<TD WIDTH="9%" VALIGN="Top" ALIGN="Left">
<P>?
</TD>
<TD WIDTH="9%" VALIGN="Top" ALIGN="Left">
<P>Comp-Appro
<P>ve
</TD>
<TD WIDTH="9%" VALIGN="Top" ALIGN="Left">
<P>End of 
<P>Design
</TD>
</TR>
<TR>
<TD WIDTH="5%" VALIGN="Top" ALIGN="Right">
<P>36
</TD>
<TD WIDTH="9%" VALIGN="Top" ALIGN="Left">
<P>BAM6968000
<P>0
</TD>
<TD WIDTH="9%" VALIGN="Top" ALIGN="Left">
<P>TRANS MOS 
<P>DMG6968U-7
<P>(20V,6.5A,
<P>1.3W)SOT23
</TD>
<TD WIDTH="9%" VALIGN="Top" ALIGN="Left">
<P>IC
</TD>
<TD WIDTH="3%" VALIGN="Top" ALIGN="Right">
<P>1
</TD>
<TD WIDTH="9%" VALIGN="Top" ALIGN="Left">
<P>DDS
</TD>
<TD WIDTH="9%" VALIGN="Top" ALIGN="Left">
<P>DMG6968U-7
</TD>
<TD WIDTH="18%" VALIGN="Top" ALIGN="Left">
<P>Q10
</TD>
<TD WIDTH="9%" VALIGN="Top" ALIGN="Left">
<P>?
</TD>
<TD WIDTH="9%" VALIGN="Top" ALIGN="Left">
<P>Comp-Appro
<P>ve
</TD>
<TD WIDTH="9%" VALIGN="Top" ALIGN="Left">
<P>End of 
<P>Design
</TD>
</TR>
<TR>
<TD WIDTH="5%" VALIGN="Top" ALIGN="Right">
<P>37
</TD>
<TD WIDTH="9%" VALIGN="Top" ALIGN="Left">
<P>BAM7002004
<P>7
</TD>
<TD WIDTH="9%" VALIGN="Top" ALIGN="Left">
<P>TRANS MOS 
<P>2N7002KDW(
<P>60V115MA,
<P>0.2W)SOT36
<P>3
</TD>
<TD WIDTH="9%" VALIGN="Top" ALIGN="Left">
<P>IC
</TD>
<TD WIDTH="3%" VALIGN="Top" ALIGN="Right">
<P>2
</TD>
<TD WIDTH="9%" VALIGN="Top" ALIGN="Left">
<P>PJT
</TD>
<TD WIDTH="9%" VALIGN="Top" ALIGN="Left">
<P>2N7002KDW
</TD>
<TD WIDTH="18%" VALIGN="Top" ALIGN="Left">
<P>Q2,Q12
</TD>
<TD WIDTH="9%" VALIGN="Top" ALIGN="Left">
<P>?
</TD>
<TD WIDTH="9%" VALIGN="Top" ALIGN="Left">
<P>?
</TD>
<TD WIDTH="9%" VALIGN="Top" ALIGN="Left">
<P>?
</TD>
</TR>
<TR>
<TD WIDTH="5%" VALIGN="Top" ALIGN="Right">
<P>38
</TD>
<TD WIDTH="9%" VALIGN="Top" ALIGN="Left">
<P>BAM7002006
<P>2
</TD>
<TD WIDTH="9%" VALIGN="Top" ALIGN="Left">
<P>TRANS MOS 
<P>NX7002AK(6
<P>0V,0.19A,
<P>0.325W)SMD
</TD>
<TD WIDTH="9%" VALIGN="Top" ALIGN="Left">
<P>IC
</TD>
<TD WIDTH="3%" VALIGN="Top" ALIGN="Right">
<P>1
</TD>
<TD WIDTH="9%" VALIGN="Top" ALIGN="Left">
<P>NXP
</TD>
<TD WIDTH="9%" VALIGN="Top" ALIGN="Left">
<P>NX7002AK
</TD>
<TD WIDTH="18%" VALIGN="Top" ALIGN="Left">
<P>Q11
</TD>
<TD WIDTH="9%" VALIGN="Top" ALIGN="Left">
<P>?
</TD>
<TD WIDTH="9%" VALIGN="Top" ALIGN="Left">
<P>Comp-Appro
<P>ve
</TD>
<TD WIDTH="9%" VALIGN="Top" ALIGN="Left">
<P>End of 
<P>Design
</TD>
</TR>
<TR>
<TD WIDTH="5%" VALIGN="Top" ALIGN="Right">
<P>39
</TD>
<TD WIDTH="9%" VALIGN="Top" ALIGN="Left">
<P>BAM7002006
<P>8
</TD>
<TD WIDTH="9%" VALIGN="Top" ALIGN="Left">
<P>TRANS MOS 
<P>2N7002A-7(
<P>60V,
<P>0.115A,
<P>0.25W)
</TD>
<TD WIDTH="9%" VALIGN="Top" ALIGN="Left">
<P>IC
</TD>
<TD WIDTH="3%" VALIGN="Top" ALIGN="Right">
<P>2
</TD>
<TD WIDTH="9%" VALIGN="Top" ALIGN="Left">
<P>DDS
</TD>
<TD WIDTH="9%" VALIGN="Top" ALIGN="Left">
<P>2N7002A-7
</TD>
<TD WIDTH="18%" VALIGN="Top" ALIGN="Left">
<P>Q6,Q8
</TD>
<TD WIDTH="9%" VALIGN="Top" ALIGN="Left">
<P>?
</TD>
<TD WIDTH="9%" VALIGN="Top" ALIGN="Left">
<P>?
</TD>
<TD WIDTH="9%" VALIGN="Top" ALIGN="Left">
<P>?
</TD>
</TR>
<TR>
<TD WIDTH="5%" VALIGN="Top" ALIGN="Right">
<P>40
</TD>
<TD WIDTH="9%" VALIGN="Top" ALIGN="Left">
<P>BC00034003
<P>3
</TD>
<TD WIDTH="9%" VALIGN="Top" ALIGN="Left">
<P>DIODE SMD 
<P>SDMK0340L-
<P>7-F(40V,
<P>30MA)
</TD>
<TD WIDTH="9%" VALIGN="Top" ALIGN="Left">
<P>IC
</TD>
<TD WIDTH="3%" VALIGN="Top" ALIGN="Right">
<P>1
</TD>
<TD WIDTH="9%" VALIGN="Top" ALIGN="Left">
<P>?
</TD>
<TD WIDTH="9%" VALIGN="Top" ALIGN="Left">
<P>?
</TD>
<TD WIDTH="18%" VALIGN="Top" ALIGN="Left">
<P>D17
</TD>
<TD WIDTH="9%" VALIGN="Top" ALIGN="Left">
<P>?
</TD>
<TD WIDTH="9%" VALIGN="Top" ALIGN="Left">
<P>?
</TD>
<TD WIDTH="9%" VALIGN="Top" ALIGN="Left">
<P>?
</TD>
</TR>
<TR>
<TD WIDTH="5%" VALIGN="Top" ALIGN="Right">
<P>41
</TD>
<TD WIDTH="9%" VALIGN="Top" ALIGN="Left">
<P>BC001240Z0
<P>1
</TD>
<TD WIDTH="9%" VALIGN="Top" ALIGN="Left">
<P>DIODE 
<P>ARRAY 
<P>DT1240E-04
<P>LP-7 
<P>(3.3V)
</TD>
<TD WIDTH="9%" VALIGN="Top" ALIGN="Left">
<P>IC
</TD>
<TD WIDTH="3%" VALIGN="Top" ALIGN="Right">
<P>4
</TD>
<TD WIDTH="9%" VALIGN="Top" ALIGN="Left">
<P>DDS
</TD>
<TD WIDTH="9%" VALIGN="Top" ALIGN="Left">
<P>DT1240E-04
<P>LP-7
</TD>
<TD WIDTH="18%" VALIGN="Top" ALIGN="Left">
<P>U16,U27,U34,U35
</TD>
<TD WIDTH="9%" VALIGN="Top" ALIGN="Left">
<P>?
</TD>
<TD WIDTH="9%" VALIGN="Top" ALIGN="Left">
<P>?
</TD>
<TD WIDTH="9%" VALIGN="Top" ALIGN="Left">
<P>?
</TD>
</TR>
<TR>
<TD WIDTH="5%" VALIGN="Top" ALIGN="Right">
<P>42
</TD>
<TD WIDTH="9%" VALIGN="Top" ALIGN="Left">
<P>BC0BAS70Z0
<P>1
</TD>
<TD WIDTH="9%" VALIGN="Top" ALIGN="Left">
<P>DIODE SMD 
<P>BAS70-05-7
<P>-F(70V,
<P>SHTKY,
<P>SOT-23)
</TD>
<TD WIDTH="9%" VALIGN="Top" ALIGN="Left">
<P>IC
</TD>
<TD WIDTH="3%" VALIGN="Top" ALIGN="Right">
<P>1
</TD>
<TD WIDTH="9%" VALIGN="Top" ALIGN="Left">
<P>DDS
</TD>
<TD WIDTH="9%" VALIGN="Top" ALIGN="Left">
<P>BAS70-05-7
<P>-F
</TD>
<TD WIDTH="18%" VALIGN="Top" ALIGN="Left">
<P>U48
</TD>
<TD WIDTH="9%" VALIGN="Top" ALIGN="Left">
<P>?
</TD>
<TD WIDTH="9%" VALIGN="Top" ALIGN="Left">
<P>Comp-Appro
<P>ve
</TD>
<TD WIDTH="9%" VALIGN="Top" ALIGN="Left">
<P>End of 
<P>Design
</TD>
</TR>
<TR>
<TD WIDTH="5%" VALIGN="Top" ALIGN="Right">
<P>43
</TD>
<TD WIDTH="9%" VALIGN="Top" ALIGN="Left">
<P>BCBAT54CZ0
<P>4
</TD>
<TD WIDTH="9%" VALIGN="Top" ALIGN="Left">
<P>DIODE SMD 
<P>BAT54C(30V
<P>,0.2A,
<P>SCHOTTKY)
</TD>
<TD WIDTH="9%" VALIGN="Top" ALIGN="Left">
<P>IC
</TD>
<TD WIDTH="3%" VALIGN="Top" ALIGN="Right">
<P>1
</TD>
<TD WIDTH="9%" VALIGN="Top" ALIGN="Left">
<P>PJT
</TD>
<TD WIDTH="9%" VALIGN="Top" ALIGN="Left">
<P>BAT54C
</TD>
<TD WIDTH="18%" VALIGN="Top" ALIGN="Left">
<P>U11
</TD>
<TD WIDTH="9%" VALIGN="Top" ALIGN="Left">
<P>?
</TD>
<TD WIDTH="9%" VALIGN="Top" ALIGN="Left">
<P>Comp-Appro
<P>ve
</TD>
<TD WIDTH="9%" VALIGN="Top" ALIGN="Left">
<P>End of 
<P>Design
</TD>
</TR>
<TR>
<TD WIDTH="5%" VALIGN="Top" ALIGN="Right">
<P>44
</TD>
<TD WIDTH="9%" VALIGN="Top" ALIGN="Left">
<P>BCSBA130Z0
<P>0
</TD>
<TD WIDTH="9%" VALIGN="Top" ALIGN="Left">
<P>DIODE SMD 
<P>SBA130Q(30
<P>V,1A,
<P>SCHOTTKY)
</TD>
<TD WIDTH="9%" VALIGN="Top" ALIGN="Left">
<P>IC
</TD>
<TD WIDTH="3%" VALIGN="Top" ALIGN="Right">
<P>1
</TD>
<TD WIDTH="9%" VALIGN="Top" ALIGN="Left">
<P>PJT
</TD>
<TD WIDTH="9%" VALIGN="Top" ALIGN="Left">
<P>SBA130Q
</TD>
<TD WIDTH="18%" VALIGN="Top" ALIGN="Left">
<P>D16
</TD>
<TD WIDTH="9%" VALIGN="Top" ALIGN="Left">
<P>?
</TD>
<TD WIDTH="9%" VALIGN="Top" ALIGN="Left">
<P>?
</TD>
<TD WIDTH="9%" VALIGN="Top" ALIGN="Left">
<P>?
</TD>
</TR>
<TR>
<TD WIDTH="5%" VALIGN="Top" ALIGN="Right">
<P>45
</TD>
<TD WIDTH="9%" VALIGN="Top" ALIGN="Left">
<P>BCSS0530Z0
<P>0
</TD>
<TD WIDTH="9%" VALIGN="Top" ALIGN="Left">
<P>DIODE SMD 
<P>SS0530(30V
<P>,0.5A)SOD-
<P>123
</TD>
<TD WIDTH="9%" VALIGN="Top" ALIGN="Left">
<P>IC
</TD>
<TD WIDTH="3%" VALIGN="Top" ALIGN="Right">
<P>1
</TD>
<TD WIDTH="9%" VALIGN="Top" ALIGN="Left">
<P>PJT
</TD>
<TD WIDTH="9%" VALIGN="Top" ALIGN="Left">
<P>SS0530
</TD>
<TD WIDTH="18%" VALIGN="Top" ALIGN="Left">
<P>D11
</TD>
<TD WIDTH="9%" VALIGN="Top" ALIGN="Left">
<P>?
</TD>
<TD WIDTH="9%" VALIGN="Top" ALIGN="Left">
<P>?
</TD>
<TD WIDTH="9%" VALIGN="Top" ALIGN="Left">
<P>?
</TD>
</TR>
<TR>
<TD WIDTH="5%" VALIGN="Top" ALIGN="Right">
<P>46
</TD>
<TD WIDTH="9%" VALIGN="Top" ALIGN="Left">
<P>BCSS0530Z0
<P>0
</TD>
<TD WIDTH="9%" VALIGN="Top" ALIGN="Left">
<P>DIODE SMD 
<P>SS0530(30V
<P>,0.5A)SOD-
<P>123
</TD>
<TD WIDTH="9%" VALIGN="Top" ALIGN="Left">
<P>EMPTY
</TD>
<TD WIDTH="3%" VALIGN="Top" ALIGN="Right">
<P>1
</TD>
<TD WIDTH="9%" VALIGN="Top" ALIGN="Left">
<P>PJT
</TD>
<TD WIDTH="9%" VALIGN="Top" ALIGN="Left">
<P>SS0530
</TD>
<TD WIDTH="18%" VALIGN="Top" ALIGN="Left">
<P>D9
</TD>
<TD WIDTH="9%" VALIGN="Top" ALIGN="Left">
<P>?
</TD>
<TD WIDTH="9%" VALIGN="Top" ALIGN="Left">
<P>?
</TD>
<TD WIDTH="9%" VALIGN="Top" ALIGN="Left">
<P>?
</TD>
</TR>
<TR>
<TD WIDTH="5%" VALIGN="Top" ALIGN="Right">
<P>47
</TD>
<TD WIDTH="9%" VALIGN="Top" ALIGN="Left">
<P>BCZA462AZ0
<P>1
</TD>
<TD WIDTH="9%" VALIGN="Top" ALIGN="Left">
<P>DIODE SMD 
<P>BZA462A(6.
<P>2V,100MA,
<P>SOT457)
</TD>
<TD WIDTH="9%" VALIGN="Top" ALIGN="Left">
<P>IC
</TD>
<TD WIDTH="3%" VALIGN="Top" ALIGN="Right">
<P>1
</TD>
<TD WIDTH="9%" VALIGN="Top" ALIGN="Left">
<P>PHI
</TD>
<TD WIDTH="9%" VALIGN="Top" ALIGN="Left">
<P>BZA462A
</TD>
<TD WIDTH="18%" VALIGN="Top" ALIGN="Left">
<P>D10
</TD>
<TD WIDTH="9%" VALIGN="Top" ALIGN="Left">
<P>?
</TD>
<TD WIDTH="9%" VALIGN="Top" ALIGN="Left">
<P>?
</TD>
<TD WIDTH="9%" VALIGN="Top" ALIGN="Left">
<P>?
</TD>
</TR>
<TR>
<TD WIDTH="5%" VALIGN="Top" ALIGN="Right">
<P>48
</TD>
<TD WIDTH="9%" VALIGN="Top" ALIGN="Left">
<P>BCZA462AZ0
<P>1
</TD>
<TD WIDTH="9%" VALIGN="Top" ALIGN="Left">
<P>DIODE SMD 
<P>BZA462A(6.
<P>2V,100MA,
<P>SOT457)
</TD>
<TD WIDTH="9%" VALIGN="Top" ALIGN="Left">
<P>EMPTY
</TD>
<TD WIDTH="3%" VALIGN="Top" ALIGN="Right">
<P>1
</TD>
<TD WIDTH="9%" VALIGN="Top" ALIGN="Left">
<P>PHI
</TD>
<TD WIDTH="9%" VALIGN="Top" ALIGN="Left">
<P>BZA462A
</TD>
<TD WIDTH="18%" VALIGN="Top" ALIGN="Left">
<P>D12
</TD>
<TD WIDTH="9%" VALIGN="Top" ALIGN="Left">
<P>?
</TD>
<TD WIDTH="9%" VALIGN="Top" ALIGN="Left">
<P>?
</TD>
<TD WIDTH="9%" VALIGN="Top" ALIGN="Left">
<P>?
</TD>
</TR>
<TR>
<TD WIDTH="5%" VALIGN="Top" ALIGN="Right">
<P>49
</TD>
<TD WIDTH="9%" VALIGN="Top" ALIGN="Left">
<P>BEBL0172Z0
<P>0
</TD>
<TD WIDTH="9%" VALIGN="Top" ALIGN="Left">
<P>LED 
<P>SMD(2P) 
<P>BLUE(LTST-
<P>C281TBKT-5
<P>A)
</TD>
<TD WIDTH="9%" VALIGN="Top" ALIGN="Left">
<P>IC
</TD>
<TD WIDTH="3%" VALIGN="Top" ALIGN="Right">
<P>2
</TD>
<TD WIDTH="9%" VALIGN="Top" ALIGN="Left">
<P>?
</TD>
<TD WIDTH="9%" VALIGN="Top" ALIGN="Left">
<P>LTST-C281T
<P>BKT-5A
</TD>
<TD WIDTH="18%" VALIGN="Top" ALIGN="Left">
<P>D18,D19
</TD>
<TD WIDTH="9%" VALIGN="Top" ALIGN="Left">
<P>?
</TD>
<TD WIDTH="9%" VALIGN="Top" ALIGN="Left">
<P>?
</TD>
<TD WIDTH="9%" VALIGN="Top" ALIGN="Left">
<P>?
</TD>
</TR>
<TR>
<TD WIDTH="5%" VALIGN="Top" ALIGN="Right">
<P>50
</TD>
<TD WIDTH="9%" VALIGN="Top" ALIGN="Left">
<P>BEBL0186D0
<P>0
</TD>
<TD WIDTH="9%" VALIGN="Top" ALIGN="Left">
<P>LED 
<P>DIP(2P)BLU
<P>E(LTL42FTB
<P>G9JH213T)
</TD>
<TD WIDTH="9%" VALIGN="Top" ALIGN="Left">
<P>IC
</TD>
<TD WIDTH="3%" VALIGN="Top" ALIGN="Right">
<P>2
</TD>
<TD WIDTH="9%" VALIGN="Top" ALIGN="Left">
<P>?
</TD>
<TD WIDTH="9%" VALIGN="Top" ALIGN="Left">
<P>LTL42FTBG9
<P>JH213T
</TD>
<TD WIDTH="18%" VALIGN="Top" ALIGN="Left">
<P>D14,D15
</TD>
<TD WIDTH="9%" VALIGN="Top" ALIGN="Left">
<P>?
</TD>
<TD WIDTH="9%" VALIGN="Top" ALIGN="Left">
<P>?
</TD>
<TD WIDTH="9%" VALIGN="Top" ALIGN="Left">
<P>?
</TD>
</TR>
<TR>
<TD WIDTH="5%" VALIGN="Top" ALIGN="Right">
<P>51
</TD>
<TD WIDTH="9%" VALIGN="Top" ALIGN="Left">
<P>BEBY0029DA
<P>0
</TD>
<TD WIDTH="9%" VALIGN="Top" ALIGN="Left">
<P>LED 
<P>DIP(3P)BLU
<P>E/YELLOW(L
<P>TL1BESTBKJ
<P>H185T)
</TD>
<TD WIDTH="9%" VALIGN="Top" ALIGN="Left">
<P>IC
</TD>
<TD WIDTH="3%" VALIGN="Top" ALIGN="Right">
<P>1
</TD>
<TD WIDTH="9%" VALIGN="Top" ALIGN="Left">
<P>LIT
</TD>
<TD WIDTH="9%" VALIGN="Top" ALIGN="Left">
<P>LTL1BESTBK
<P>JH185T
</TD>
<TD WIDTH="18%" VALIGN="Top" ALIGN="Left">
<P>LED90
</TD>
<TD WIDTH="9%" VALIGN="Top" ALIGN="Left">
<P>?
</TD>
<TD WIDTH="9%" VALIGN="Top" ALIGN="Left">
<P>?
</TD>
<TD WIDTH="9%" VALIGN="Top" ALIGN="Left">
<P>?
</TD>
</TR>
<TR>
<TD WIDTH="5%" VALIGN="Top" ALIGN="Right">
<P>52
</TD>
<TD WIDTH="9%" VALIGN="Top" ALIGN="Left">
<P>BEGR0278Z0
<P>0
</TD>
<TD WIDTH="9%" VALIGN="Top" ALIGN="Left">
<P>LED 
<P>SMD(2P) 
<P>GREEN(19-2
<P>13/GVC-AMN
<P>B/3T)
</TD>
<TD WIDTH="9%" VALIGN="Top" ALIGN="Left">
<P>IC
</TD>
<TD WIDTH="3%" VALIGN="Top" ALIGN="Right">
<P>5
</TD>
<TD WIDTH="9%" VALIGN="Top" ALIGN="Left">
<P>?
</TD>
<TD WIDTH="9%" VALIGN="Top" ALIGN="Left">
<P>19-213/GVC
<P>-AMNB/3T
</TD>
<TD WIDTH="18%" VALIGN="Top" ALIGN="Left">
<P>D0,D1,D2,D3,D8
</TD>
<TD WIDTH="9%" VALIGN="Top" ALIGN="Left">
<P>?
</TD>
<TD WIDTH="9%" VALIGN="Top" ALIGN="Left">
<P>?
</TD>
<TD WIDTH="9%" VALIGN="Top" ALIGN="Left">
<P>?
</TD>
</TR>
<TR>
<TD WIDTH="5%" VALIGN="Top" ALIGN="Right">
<P>53
</TD>
<TD WIDTH="9%" VALIGN="Top" ALIGN="Left">
<P>BERD0034Z0
<P>7
</TD>
<TD WIDTH="9%" VALIGN="Top" ALIGN="Left">
<P>LED 
<P>SMD(2P) 
<P>RED 
<P>(19-217/R6
<P>C-P1Q2/3T)
</TD>
<TD WIDTH="9%" VALIGN="Top" ALIGN="Left">
<P>IC
</TD>
<TD WIDTH="3%" VALIGN="Top" ALIGN="Right">
<P>4
</TD>
<TD WIDTH="9%" VALIGN="Top" ALIGN="Left">
<P>?
</TD>
<TD WIDTH="9%" VALIGN="Top" ALIGN="Left">
<P>19-217/R6C
<P>-P1Q2/3T
</TD>
<TD WIDTH="18%" VALIGN="Top" ALIGN="Left">
<P>D4,D5,D6,D7
</TD>
<TD WIDTH="9%" VALIGN="Top" ALIGN="Left">
<P>?
</TD>
<TD WIDTH="9%" VALIGN="Top" ALIGN="Left">
<P>?
</TD>
<TD WIDTH="9%" VALIGN="Top" ALIGN="Left">
<P>?
</TD>
</TR>
<TR>
<TD WIDTH="5%" VALIGN="Top" ALIGN="Right">
<P>54
</TD>
<TD WIDTH="9%" VALIGN="Top" ALIGN="Left">
<P>BEYL0123D0
<P>0
</TD>
<TD WIDTH="9%" VALIGN="Top" ALIGN="Left">
<P>LED(DIP)YE
<P>LLOW(LTL42
<P>NKSDH213)
</TD>
<TD WIDTH="9%" VALIGN="Top" ALIGN="Left">
<P>IC
</TD>
<TD WIDTH="3%" VALIGN="Top" ALIGN="Right">
<P>1
</TD>
<TD WIDTH="9%" VALIGN="Top" ALIGN="Left">
<P>?
</TD>
<TD WIDTH="9%" VALIGN="Top" ALIGN="Left">
<P>LTL42NKSDH
<P>213
</TD>
<TD WIDTH="18%" VALIGN="Top" ALIGN="Left">
<P>D13
</TD>
<TD WIDTH="9%" VALIGN="Top" ALIGN="Left">
<P>?
</TD>
<TD WIDTH="9%" VALIGN="Top" ALIGN="Left">
<P>?
</TD>
<TD WIDTH="9%" VALIGN="Top" ALIGN="Left">
<P>?
</TD>
</TR>
<TR>
<TD WIDTH="5%" VALIGN="Top" ALIGN="Right">
<P>55
</TD>
<TD WIDTH="9%" VALIGN="Top" ALIGN="Left">
<P>BF62500002
<P>3
</TD>
<TD WIDTH="9%" VALIGN="Top" ALIGN="Left">
<P>OSC SMD 
<P>25MHZ(+-25
<P>PPM,
<P>3.3V)7X250
<P>00018
</TD>
<TD WIDTH="9%" VALIGN="Top" ALIGN="Left">
<P>MISC
</TD>
<TD WIDTH="3%" VALIGN="Top" ALIGN="Right">
<P>2
</TD>
<TD WIDTH="9%" VALIGN="Top" ALIGN="Left">
<P>TXC
</TD>
<TD WIDTH="9%" VALIGN="Top" ALIGN="Left">
<P>7X25000018
</TD>
<TD WIDTH="18%" VALIGN="Top" ALIGN="Left">
<P>OSC1,OSC2
</TD>
<TD WIDTH="9%" VALIGN="Top" ALIGN="Left">
<P>?
</TD>
<TD WIDTH="9%" VALIGN="Top" ALIGN="Left">
<P>?
</TD>
<TD WIDTH="9%" VALIGN="Top" ALIGN="Left">
<P>?
</TD>
</TR>
<TR>
<TD WIDTH="5%" VALIGN="Top" ALIGN="Right">
<P>56
</TD>
<TD WIDTH="9%" VALIGN="Top" ALIGN="Left">
<P>CH0106F0B0
<P>0
</TD>
<TD WIDTH="9%" VALIGN="Top" ALIGN="Left">
<P>CHIP0402
</TD>
<TD WIDTH="9%" VALIGN="Top" ALIGN="Left">
<P>NPO
</TD>
<TD WIDTH="3%" VALIGN="Top" ALIGN="Right">
<P>5
</TD>
<TD WIDTH="9%" VALIGN="Top" ALIGN="Left">
<P>?
</TD>
<TD WIDTH="9%" VALIGN="Top" ALIGN="Left">
<P>?
</TD>
<TD WIDTH="18%" VALIGN="Top" ALIGN="Left">
<P>C205,C206,C207,C211,
<P>C212
</TD>
<TD WIDTH="9%" VALIGN="Top" ALIGN="Left">
<P>?
</TD>
<TD WIDTH="9%" VALIGN="Top" ALIGN="Left">
<P>?
</TD>
<TD WIDTH="9%" VALIGN="Top" ALIGN="Left">
<P>?
</TD>
</TR>
<TR>
<TD WIDTH="5%" VALIGN="Top" ALIGN="Right">
<P>57
</TD>
<TD WIDTH="9%" VALIGN="Top" ALIGN="Left">
<P>CH0336F0B0
<P>0
</TD>
<TD WIDTH="9%" VALIGN="Top" ALIGN="Left">
<P>CAP CHIP 
<P>33P 
<P>50V(+-1%,
<P>C0G,0402)
</TD>
<TD WIDTH="9%" VALIGN="Top" ALIGN="Left">
<P>C0G
</TD>
<TD WIDTH="3%" VALIGN="Top" ALIGN="Right">
<P>3
</TD>
<TD WIDTH="9%" VALIGN="Top" ALIGN="Left">
<P>?
</TD>
<TD WIDTH="9%" VALIGN="Top" ALIGN="Left">
<P>?
</TD>
<TD WIDTH="18%" VALIGN="Top" ALIGN="Left">
<P>C208,C209,C210
</TD>
<TD WIDTH="9%" VALIGN="Top" ALIGN="Left">
<P>?
</TD>
<TD WIDTH="9%" VALIGN="Top" ALIGN="Left">
<P>?
</TD>
<TD WIDTH="9%" VALIGN="Top" ALIGN="Left">
<P>?
</TD>
</TR>
<TR>
<TD WIDTH="5%" VALIGN="Top" ALIGN="Right">
<P>58
</TD>
<TD WIDTH="9%" VALIGN="Top" ALIGN="Left">
<P>CH06806JB0
<P>1
</TD>
<TD WIDTH="9%" VALIGN="Top" ALIGN="Left">
<P>CAP CHIP 
<P>68P 
<P>50V(+-5%.C
<P>OG.0402)
</TD>
<TD WIDTH="9%" VALIGN="Top" ALIGN="Left">
<P>COG
</TD>
<TD WIDTH="3%" VALIGN="Top" ALIGN="Right">
<P>1
</TD>
<TD WIDTH="9%" VALIGN="Top" ALIGN="Left">
<P>?
</TD>
<TD WIDTH="9%" VALIGN="Top" ALIGN="Left">
<P>?
</TD>
<TD WIDTH="18%" VALIGN="Top" ALIGN="Left">
<P>PC272
</TD>
<TD WIDTH="9%" VALIGN="Top" ALIGN="Left">
<P>?
</TD>
<TD WIDTH="9%" VALIGN="Top" ALIGN="Left">
<P>?
</TD>
<TD WIDTH="9%" VALIGN="Top" ALIGN="Left">
<P>?
</TD>
</TR>
<TR>
<TD WIDTH="5%" VALIGN="Top" ALIGN="Right">
<P>59
</TD>
<TD WIDTH="9%" VALIGN="Top" ALIGN="Left">
<P>CH11006JB0
<P>0
</TD>
<TD WIDTH="9%" VALIGN="Top" ALIGN="Left">
<P>CAP CHIP 
<P>100P 
<P>50V(+-5%,
<P>NPO,0402)
</TD>
<TD WIDTH="9%" VALIGN="Top" ALIGN="Left">
<P>NPO
</TD>
<TD WIDTH="3%" VALIGN="Top" ALIGN="Right">
<P>3
</TD>
<TD WIDTH="9%" VALIGN="Top" ALIGN="Left">
<P>?
</TD>
<TD WIDTH="9%" VALIGN="Top" ALIGN="Left">
<P>?
</TD>
<TD WIDTH="18%" VALIGN="Top" ALIGN="Left">
<P>C9,C275,PC239
</TD>
<TD WIDTH="9%" VALIGN="Top" ALIGN="Left">
<P>?
</TD>
<TD WIDTH="9%" VALIGN="Top" ALIGN="Left">
<P>?
</TD>
<TD WIDTH="9%" VALIGN="Top" ALIGN="Left">
<P>?
</TD>
</TR>
<TR>
<TD WIDTH="5%" VALIGN="Top" ALIGN="Right">
<P>60
</TD>
<TD WIDTH="9%" VALIGN="Top" ALIGN="Left">
<P>CH11006JB1
<P>8
</TD>
<TD WIDTH="9%" VALIGN="Top" ALIGN="Left">
<P>CAP CHIP 
<P>100P 
<P>50V(+-5%.X
<P>7R.0402)
</TD>
<TD WIDTH="9%" VALIGN="Top" ALIGN="Left">
<P>EMPTY
</TD>
<TD WIDTH="3%" VALIGN="Top" ALIGN="Right">
<P>2
</TD>
<TD WIDTH="9%" VALIGN="Top" ALIGN="Left">
<P>?
</TD>
<TD WIDTH="9%" VALIGN="Top" ALIGN="Left">
<P>?
</TD>
<TD WIDTH="18%" VALIGN="Top" ALIGN="Left">
<P>C213,C214
</TD>
<TD WIDTH="9%" VALIGN="Top" ALIGN="Left">
<P>?
</TD>
<TD WIDTH="9%" VALIGN="Top" ALIGN="Left">
<P>Comp-Appro
<P>ve
</TD>
<TD WIDTH="9%" VALIGN="Top" ALIGN="Left">
<P>End of 
<P>Design
</TD>
</TR>
<TR>
<TD WIDTH="5%" VALIGN="Top" ALIGN="Right">
<P>61
</TD>
<TD WIDTH="9%" VALIGN="Top" ALIGN="Left">
<P>CH14706KB1
<P>8
</TD>
<TD WIDTH="9%" VALIGN="Top" ALIGN="Left">
<P>CHIP0402
</TD>
<TD WIDTH="9%" VALIGN="Top" ALIGN="Left">
<P>X7R
</TD>
<TD WIDTH="3%" VALIGN="Top" ALIGN="Right">
<P>5
</TD>
<TD WIDTH="9%" VALIGN="Top" ALIGN="Left">
<P>?
</TD>
<TD WIDTH="9%" VALIGN="Top" ALIGN="Left">
<P>?
</TD>
<TD WIDTH="18%" VALIGN="Top" ALIGN="Left">
<P>C172,C178,C179,C324,
<P>C326
</TD>
<TD WIDTH="9%" VALIGN="Top" ALIGN="Left">
<P>?
</TD>
<TD WIDTH="9%" VALIGN="Top" ALIGN="Left">
<P>?
</TD>
<TD WIDTH="9%" VALIGN="Top" ALIGN="Left">
<P>?
</TD>
</TR>
<TR>
<TD WIDTH="5%" VALIGN="Top" ALIGN="Right">
<P>62
</TD>
<TD WIDTH="9%" VALIGN="Top" ALIGN="Left">
<P>CH22206KB1
<P>6
</TD>
<TD WIDTH="9%" VALIGN="Top" ALIGN="Left">
<P>CAP CHIP 
<P>2200P 
<P>50V(+-10%,
<P>X7R,0402)
</TD>
<TD WIDTH="9%" VALIGN="Top" ALIGN="Left">
<P>X7R
</TD>
<TD WIDTH="3%" VALIGN="Top" ALIGN="Right">
<P>1
</TD>
<TD WIDTH="9%" VALIGN="Top" ALIGN="Left">
<P>?
</TD>
<TD WIDTH="9%" VALIGN="Top" ALIGN="Left">
<P>?
</TD>
<TD WIDTH="18%" VALIGN="Top" ALIGN="Left">
<P>C63
</TD>
<TD WIDTH="9%" VALIGN="Top" ALIGN="Left">
<P>?
</TD>
<TD WIDTH="9%" VALIGN="Top" ALIGN="Left">
<P>?
</TD>
<TD WIDTH="9%" VALIGN="Top" ALIGN="Left">
<P>?
</TD>
</TR>
<TR>
<TD WIDTH="5%" VALIGN="Top" ALIGN="Right">
<P>63
</TD>
<TD WIDTH="9%" VALIGN="Top" ALIGN="Left">
<P>CH2336K1B1
<P>2
</TD>
<TD WIDTH="9%" VALIGN="Top" ALIGN="Left">
<P>CHIP0402
</TD>
<TD WIDTH="9%" VALIGN="Top" ALIGN="Left">
<P>X7R
</TD>
<TD WIDTH="3%" VALIGN="Top" ALIGN="Right">
<P>1
</TD>
<TD WIDTH="9%" VALIGN="Top" ALIGN="Left">
<P>?
</TD>
<TD WIDTH="9%" VALIGN="Top" ALIGN="Left">
<P>?
</TD>
<TD WIDTH="18%" VALIGN="Top" ALIGN="Left">
<P>PC273
</TD>
<TD WIDTH="9%" VALIGN="Top" ALIGN="Left">
<P>?
</TD>
<TD WIDTH="9%" VALIGN="Top" ALIGN="Left">
<P>?
</TD>
<TD WIDTH="9%" VALIGN="Top" ALIGN="Left">
<P>?
</TD>
</TR>
<TR>
<TD WIDTH="5%" VALIGN="Top" ALIGN="Right">
<P>64
</TD>
<TD WIDTH="9%" VALIGN="Top" ALIGN="Left">
<P>CH2474K1B0
<P>8
</TD>
<TD WIDTH="9%" VALIGN="Top" ALIGN="Left">
<P>CAP CHIP 
<P>4700P 
<P>25V(+-10%,
<P>X7R,
<P>0402)MUR
</TD>
<TD WIDTH="9%" VALIGN="Top" ALIGN="Left">
<P>EMPTY
</TD>
<TD WIDTH="3%" VALIGN="Top" ALIGN="Right">
<P>1
</TD>
<TD WIDTH="9%" VALIGN="Top" ALIGN="Left">
<P>?
</TD>
<TD WIDTH="9%" VALIGN="Top" ALIGN="Left">
<P>?
</TD>
<TD WIDTH="18%" VALIGN="Top" ALIGN="Left">
<P>C223
</TD>
<TD WIDTH="9%" VALIGN="Top" ALIGN="Left">
<P>?
</TD>
<TD WIDTH="9%" VALIGN="Top" ALIGN="Left">
<P>?
</TD>
<TD WIDTH="9%" VALIGN="Top" ALIGN="Left">
<P>?
</TD>
</TR>
<TR>
<TD WIDTH="5%" VALIGN="Top" ALIGN="Right">
<P>65
</TD>
<TD WIDTH="9%" VALIGN="Top" ALIGN="Left">
<P>CH30106KB1
<P>9
</TD>
<TD WIDTH="9%" VALIGN="Top" ALIGN="Left">
<P>CAP CHIP 
<P>0.001U 
<P>50V(10%,
<P>X7R,0402)
</TD>
<TD WIDTH="9%" VALIGN="Top" ALIGN="Left">
<P>X7R
</TD>
<TD WIDTH="3%" VALIGN="Top" ALIGN="Right">
<P>6
</TD>
<TD WIDTH="9%" VALIGN="Top" ALIGN="Left">
<P>?
</TD>
<TD WIDTH="9%" VALIGN="Top" ALIGN="Left">
<P>?
</TD>
<TD WIDTH="18%" VALIGN="Top" ALIGN="Left">
<P>C150,C151,C153,C154,
<P>C155,C156
</TD>
<TD WIDTH="9%" VALIGN="Top" ALIGN="Left">
<P>?
</TD>
<TD WIDTH="9%" VALIGN="Top" ALIGN="Left">
<P>Comp-Relea
<P>se Qty
</TD>
<TD WIDTH="9%" VALIGN="Top" ALIGN="Left">
<P>End of 
<P>Design
</TD>
</TR>
<TR>
<TD WIDTH="5%" VALIGN="Top" ALIGN="Right">
<P>66
</TD>
<TD WIDTH="9%" VALIGN="Top" ALIGN="Left">
<P>CH31006KB1
<P>8
</TD>
<TD WIDTH="9%" VALIGN="Top" ALIGN="Left">
<P>CAP CHIP 
<P>0.01U 
<P>50V(+-10%,
<P>X7R,0402)
</TD>
<TD WIDTH="9%" VALIGN="Top" ALIGN="Left">
<P>X7R
</TD>
<TD WIDTH="3%" VALIGN="Top" ALIGN="Right">
<P>10
</TD>
<TD WIDTH="9%" VALIGN="Top" ALIGN="Left">
<P>?
</TD>
<TD WIDTH="9%" VALIGN="Top" ALIGN="Left">
<P>?
</TD>
<TD WIDTH="18%" VALIGN="Top" ALIGN="Left">
<P>C133,C134,C135,C136,
<P>C137,C138,C170,C246,
<P>C258,C259
</TD>
<TD WIDTH="9%" VALIGN="Top" ALIGN="Left">
<P>?
</TD>
<TD WIDTH="9%" VALIGN="Top" ALIGN="Left">
<P>?
</TD>
<TD WIDTH="9%" VALIGN="Top" ALIGN="Left">
<P>?
</TD>
</TR>
<TR>
<TD WIDTH="5%" VALIGN="Top" ALIGN="Right">
<P>67
</TD>
<TD WIDTH="9%" VALIGN="Top" ALIGN="Left">
<P>CH31006KB1
<P>8
</TD>
<TD WIDTH="9%" VALIGN="Top" ALIGN="Left">
<P>CAP CHIP 
<P>0.01U 
<P>50V(+-10%,
<P>X7R,0402)
</TD>
<TD WIDTH="9%" VALIGN="Top" ALIGN="Left">
<P>EMPTY
</TD>
<TD WIDTH="3%" VALIGN="Top" ALIGN="Right">
<P>6
</TD>
<TD WIDTH="9%" VALIGN="Top" ALIGN="Left">
<P>?
</TD>
<TD WIDTH="9%" VALIGN="Top" ALIGN="Left">
<P>?
</TD>
<TD WIDTH="18%" VALIGN="Top" ALIGN="Left">
<P>C21,C169,C281,C283,
<P>C285,C286
</TD>
<TD WIDTH="9%" VALIGN="Top" ALIGN="Left">
<P>?
</TD>
<TD WIDTH="9%" VALIGN="Top" ALIGN="Left">
<P>?
</TD>
<TD WIDTH="9%" VALIGN="Top" ALIGN="Left">
<P>?
</TD>
</TR>
<TR>
<TD WIDTH="5%" VALIGN="Top" ALIGN="Right">
<P>68
</TD>
<TD WIDTH="9%" VALIGN="Top" ALIGN="Left">
<P>CH4104K1B0
<P>0
</TD>
<TD WIDTH="9%" VALIGN="Top" ALIGN="Left">
<P>CAP CHIP 
<P>0.1U 
<P>25V(+-10%,
<P>X7R,0402)
</TD>
<TD WIDTH="9%" VALIGN="Top" ALIGN="Left">
<P>X7R
</TD>
<TD WIDTH="3%" VALIGN="Top" ALIGN="Right">
<P>168
</TD>
<TD WIDTH="9%" VALIGN="Top" ALIGN="Left">
<P>?
</TD>
<TD WIDTH="9%" VALIGN="Top" ALIGN="Left">
<P>?
</TD>
<TD WIDTH="18%" VALIGN="Top" ALIGN="Left">
<P>C6,C7,C8,C10,C13,
<P>C14,C17,C18,C19,C20,
<P>C22,C23,C24,C25,C26,
<P>C27,C28,C29,C31,C33,
<P>C34,C36,C37,C39,C41,
<P>C45,C49,C50,C51,C54,
<P>C57,C59,C65,C66,C68,
<P>C69,C70,C71,C72,C73,
<P>C74,C76,C77,C79,C81,
<P>C82,C83,C84,C85,C86,
<P>C87,C88,C89,C91,C92,
<P>C93,C94,C95,C96,C97,
<P>C98,C99,C100,C101,
<P>C102,C103,C105,C107,
<P>C109,C112,C130,C139,
<P>C140,C141,C144,C146,
<P>C147,C148,C149,C152,
<P>C157,C158,C159,C160,
<P>C162,C167,C168,C173,
<P>C174,C175,C180,C182,
<P>C185,C186,C187,C188,
<P>C189,C190,C191,C192,
<P>C193,C197,C200,C201,
<P>C202,C203,C217,C219,
<P>C220,C221,C222,C225,
<P>C236,C237,C240,C241,
<P>C242,C243,C245,C247,
<P>C249,C250,C251,C253,
<P>C254,C255,C260,C261,
<P>C262,C263,C264,C266,
<P>C268,C269,C271,C272,
<P>C274,C276,C278,C279,
<P>C280,C284,C290,C295,
<P>C299,C300,C303,C307,
<P>C308,C309,C311,C314,
<P>C318,C321,C500,C501,
<P>PC205,PC210,PC212,
<P>PC223,PC225,PC235,
<P>PC249,PC253,PC255,
<P>PC263,PC266,PC271
</TD>
<TD WIDTH="9%" VALIGN="Top" ALIGN="Left">
<P>?
</TD>
<TD WIDTH="9%" VALIGN="Top" ALIGN="Left">
<P>?
</TD>
<TD WIDTH="9%" VALIGN="Top" ALIGN="Left">
<P>?
</TD>
</TR>
<TR>
<TD WIDTH="5%" VALIGN="Top" ALIGN="Right">
<P>69
</TD>
<TD WIDTH="9%" VALIGN="Top" ALIGN="Left">
<P>CH4104K1B0
<P>0
</TD>
<TD WIDTH="9%" VALIGN="Top" ALIGN="Left">
<P>CAP CHIP 
<P>0.1U 
<P>25V(+-10%,
<P>X7R,0402)
</TD>
<TD WIDTH="9%" VALIGN="Top" ALIGN="Left">
<P>EMPTY
</TD>
<TD WIDTH="3%" VALIGN="Top" ALIGN="Right">
<P>11
</TD>
<TD WIDTH="9%" VALIGN="Top" ALIGN="Left">
<P>?
</TD>
<TD WIDTH="9%" VALIGN="Top" ALIGN="Left">
<P>?
</TD>
<TD WIDTH="18%" VALIGN="Top" ALIGN="Left">
<P>C11,C226,C227,C228,
<P>C230,C233,C235,C238,
<P>C239,C304,C306
</TD>
<TD WIDTH="9%" VALIGN="Top" ALIGN="Left">
<P>?
</TD>
<TD WIDTH="9%" VALIGN="Top" ALIGN="Left">
<P>?
</TD>
<TD WIDTH="9%" VALIGN="Top" ALIGN="Left">
<P>?
</TD>
</TR>
<TR>
<TD WIDTH="5%" VALIGN="Top" ALIGN="Right">
<P>70
</TD>
<TD WIDTH="9%" VALIGN="Top" ALIGN="Left">
<P>CH4223K1B0
<P>0
</TD>
<TD WIDTH="9%" VALIGN="Top" ALIGN="Left">
<P>CAP CHIP 
<P>0.22U 
<P>16V(10%,
<P>X7R,0402)
</TD>
<TD WIDTH="9%" VALIGN="Top" ALIGN="Left">
<P>X7R
</TD>
<TD WIDTH="3%" VALIGN="Top" ALIGN="Right">
<P>5
</TD>
<TD WIDTH="9%" VALIGN="Top" ALIGN="Left">
<P>?
</TD>
<TD WIDTH="9%" VALIGN="Top" ALIGN="Left">
<P>?
</TD>
<TD WIDTH="18%" VALIGN="Top" ALIGN="Left">
<P>C12,PC216,PC224,
<P>PC254,PC264
</TD>
<TD WIDTH="9%" VALIGN="Top" ALIGN="Left">
<P>?
</TD>
<TD WIDTH="9%" VALIGN="Top" ALIGN="Left">
<P>Comp-Appro
<P>ve
</TD>
<TD WIDTH="9%" VALIGN="Top" ALIGN="Left">
<P>End of 
<P>Design
</TD>
</TR>
<TR>
<TD WIDTH="5%" VALIGN="Top" ALIGN="Right">
<P>71
</TD>
<TD WIDTH="9%" VALIGN="Top" ALIGN="Left">
<P>CH4223K1B0
<P>0
</TD>
<TD WIDTH="9%" VALIGN="Top" ALIGN="Left">
<P>CAP CHIP 
<P>0.22U 
<P>16V(10%,
<P>X7R,0402)
</TD>
<TD WIDTH="9%" VALIGN="Top" ALIGN="Left">
<P>EMPTY
</TD>
<TD WIDTH="3%" VALIGN="Top" ALIGN="Right">
<P>1
</TD>
<TD WIDTH="9%" VALIGN="Top" ALIGN="Left">
<P>?
</TD>
<TD WIDTH="9%" VALIGN="Top" ALIGN="Left">
<P>?
</TD>
<TD WIDTH="18%" VALIGN="Top" ALIGN="Left">
<P>C229
</TD>
<TD WIDTH="9%" VALIGN="Top" ALIGN="Left">
<P>?
</TD>
<TD WIDTH="9%" VALIGN="Top" ALIGN="Left">
<P>Comp-Appro
<P>ve
</TD>
<TD WIDTH="9%" VALIGN="Top" ALIGN="Left">
<P>End of 
<P>Design
</TD>
</TR>
<TR>
<TD WIDTH="5%" VALIGN="Top" ALIGN="Right">
<P>72
</TD>
<TD WIDTH="9%" VALIGN="Top" ALIGN="Left">
<P>CH5101KEB0
<P>0
</TD>
<TD WIDTH="9%" VALIGN="Top" ALIGN="Left">
<P>CAP CHIP 
<P>1U 
<P>6.3V(+-10%
<P>,X6S,0402)
</TD>
<TD WIDTH="9%" VALIGN="Top" ALIGN="Left">
<P>EMPTY
</TD>
<TD WIDTH="3%" VALIGN="Top" ALIGN="Right">
<P>1
</TD>
<TD WIDTH="9%" VALIGN="Top" ALIGN="Left">
<P>?
</TD>
<TD WIDTH="9%" VALIGN="Top" ALIGN="Left">
<P>?
</TD>
<TD WIDTH="18%" VALIGN="Top" ALIGN="Left">
<P>C231
</TD>
<TD WIDTH="9%" VALIGN="Top" ALIGN="Left">
<P>?
</TD>
<TD WIDTH="9%" VALIGN="Top" ALIGN="Left">
<P>Comp-Appro
<P>ve
</TD>
<TD WIDTH="9%" VALIGN="Top" ALIGN="Left">
<P>End of 
<P>Design
</TD>
</TR>
<TR>
<TD WIDTH="5%" VALIGN="Top" ALIGN="Right">
<P>73
</TD>
<TD WIDTH="9%" VALIGN="Top" ALIGN="Left">
<P>CH5103K190
<P>0
</TD>
<TD WIDTH="9%" VALIGN="Top" ALIGN="Left">
<P>CHIP0603
</TD>
<TD WIDTH="9%" VALIGN="Top" ALIGN="Left">
<P>EMPTY
</TD>
<TD WIDTH="3%" VALIGN="Top" ALIGN="Right">
<P>1
</TD>
<TD WIDTH="9%" VALIGN="Top" ALIGN="Left">
<P>?
</TD>
<TD WIDTH="9%" VALIGN="Top" ALIGN="Left">
<P>?
</TD>
<TD WIDTH="18%" VALIGN="Top" ALIGN="Left">
<P>C204
</TD>
<TD WIDTH="9%" VALIGN="Top" ALIGN="Left">
<P>?
</TD>
<TD WIDTH="9%" VALIGN="Top" ALIGN="Left">
<P>Comp-Appro
<P>ve
</TD>
<TD WIDTH="9%" VALIGN="Top" ALIGN="Left">
<P>End of 
<P>Design
</TD>
</TR>
<TR>
<TD WIDTH="5%" VALIGN="Top" ALIGN="Right">
<P>74
</TD>
<TD WIDTH="9%" VALIGN="Top" ALIGN="Left">
<P>CH5103K9B0
<P>0
</TD>
<TD WIDTH="9%" VALIGN="Top" ALIGN="Left">
<P>CHIP0402
</TD>
<TD WIDTH="9%" VALIGN="Top" ALIGN="Left">
<P>EMPTY
</TD>
<TD WIDTH="3%" VALIGN="Top" ALIGN="Right">
<P>4
</TD>
<TD WIDTH="9%" VALIGN="Top" ALIGN="Left">
<P>?
</TD>
<TD WIDTH="9%" VALIGN="Top" ALIGN="Left">
<P>?
</TD>
<TD WIDTH="18%" VALIGN="Top" ALIGN="Left">
<P>C181,C267,C270,C273
</TD>
<TD WIDTH="9%" VALIGN="Top" ALIGN="Left">
<P>?
</TD>
<TD WIDTH="9%" VALIGN="Top" ALIGN="Left">
<P>Comp-Appro
<P>ve
</TD>
<TD WIDTH="9%" VALIGN="Top" ALIGN="Left">
<P>End of 
<P>Design
</TD>
</TR>
<TR>
<TD WIDTH="5%" VALIGN="Top" ALIGN="Right">
<P>75
</TD>
<TD WIDTH="9%" VALIGN="Top" ALIGN="Left">
<P>CH5104KEB0
<P>2
</TD>
<TD WIDTH="9%" VALIGN="Top" ALIGN="Left">
<P>CAP CHIP 
<P>1UF 
<P>25V(+-10%,
<P>X6S,0402)
</TD>
<TD WIDTH="9%" VALIGN="Top" ALIGN="Left">
<P>X6S
</TD>
<TD WIDTH="3%" VALIGN="Top" ALIGN="Right">
<P>63
</TD>
<TD WIDTH="9%" VALIGN="Top" ALIGN="Left">
<P>?
</TD>
<TD WIDTH="9%" VALIGN="Top" ALIGN="Left">
<P>?
</TD>
<TD WIDTH="18%" VALIGN="Top" ALIGN="Left">
<P>C2,C3,C4,C5,C30,C32,
<P>C35,C38,C43,C46,C47,
<P>C48,C52,C53,C56,C58,
<P>C60,C61,C62,C64,C67,
<P>C75,C78,C80,C90,
<P>C104,C106,C108,C110,
<P>C111,C114,C115,C116,
<P>C117,C119,C122,C127,
<P>C128,C129,C145,C161,
<P>C164,C165,C166,C176,
<P>C195,C196,C198,C199,
<P>C216,C218,C244,C252,
<P>C256,C257,C277,C282,
<P>PC208,PC221,PC233,
<P>PC243,PC250,PC260
</TD>
<TD WIDTH="9%" VALIGN="Top" ALIGN="Left">
<P>?
</TD>
<TD WIDTH="9%" VALIGN="Top" ALIGN="Left">
<P>?
</TD>
<TD WIDTH="9%" VALIGN="Top" ALIGN="Left">
<P>?
</TD>
</TR>
<TR>
<TD WIDTH="5%" VALIGN="Top" ALIGN="Right">
<P>76
</TD>
<TD WIDTH="9%" VALIGN="Top" ALIGN="Left">
<P>CH5472K9B0
<P>0
</TD>
<TD WIDTH="9%" VALIGN="Top" ALIGN="Left">
<P>CAP CHIP 
<P>4.7U 
<P>10V(+-10%,
<P>X5R,0402)
</TD>
<TD WIDTH="9%" VALIGN="Top" ALIGN="Left">
<P>X5R
</TD>
<TD WIDTH="3%" VALIGN="Top" ALIGN="Right">
<P>2
</TD>
<TD WIDTH="9%" VALIGN="Top" ALIGN="Left">
<P>?
</TD>
<TD WIDTH="9%" VALIGN="Top" ALIGN="Left">
<P>?
</TD>
<TD WIDTH="18%" VALIGN="Top" ALIGN="Left">
<P>C40,C44
</TD>
<TD WIDTH="9%" VALIGN="Top" ALIGN="Left">
<P>?
</TD>
<TD WIDTH="9%" VALIGN="Top" ALIGN="Left">
<P>?
</TD>
<TD WIDTH="9%" VALIGN="Top" ALIGN="Left">
<P>?
</TD>
</TR>
<TR>
<TD WIDTH="5%" VALIGN="Top" ALIGN="Right">
<P>77
</TD>
<TD WIDTH="9%" VALIGN="Top" ALIGN="Left">
<P>CH5474KE90
<P>6
</TD>
<TD WIDTH="9%" VALIGN="Top" ALIGN="Left">
<P>CAP CHIP 
<P>4.7UF 
<P>25V(+-10%,
<P>X6S,0603)
</TD>
<TD WIDTH="9%" VALIGN="Top" ALIGN="Left">
<P>X6S
</TD>
<TD WIDTH="3%" VALIGN="Top" ALIGN="Right">
<P>1
</TD>
<TD WIDTH="9%" VALIGN="Top" ALIGN="Left">
<P>?
</TD>
<TD WIDTH="9%" VALIGN="Top" ALIGN="Left">
<P>?
</TD>
<TD WIDTH="18%" VALIGN="Top" ALIGN="Left">
<P>C1
</TD>
<TD WIDTH="9%" VALIGN="Top" ALIGN="Left">
<P>?
</TD>
<TD WIDTH="9%" VALIGN="Top" ALIGN="Left">
<P>?
</TD>
<TD WIDTH="9%" VALIGN="Top" ALIGN="Left">
<P>?
</TD>
</TR>
<TR>
<TD WIDTH="5%" VALIGN="Top" ALIGN="Right">
<P>78
</TD>
<TD WIDTH="9%" VALIGN="Top" ALIGN="Left">
<P>CH6101MEB0
<P>1
</TD>
<TD WIDTH="9%" VALIGN="Top" ALIGN="Left">
<P>CAP CHIP 
<P>10UF 
<P>6.3V(+-20%
<P>,X6S,0402)
</TD>
<TD WIDTH="9%" VALIGN="Top" ALIGN="Left">
<P>X6S
</TD>
<TD WIDTH="3%" VALIGN="Top" ALIGN="Right">
<P>6
</TD>
<TD WIDTH="9%" VALIGN="Top" ALIGN="Left">
<P>?
</TD>
<TD WIDTH="9%" VALIGN="Top" ALIGN="Left">
<P>?
</TD>
<TD WIDTH="18%" VALIGN="Top" ALIGN="Left">
<P>C15,C16,C143,C215,
<P>C224,C248
</TD>
<TD WIDTH="9%" VALIGN="Top" ALIGN="Left">
<P>?
</TD>
<TD WIDTH="9%" VALIGN="Top" ALIGN="Left">
<P>?
</TD>
<TD WIDTH="9%" VALIGN="Top" ALIGN="Left">
<P>?
</TD>
</TR>
<TR>
<TD WIDTH="5%" VALIGN="Top" ALIGN="Right">
<P>79
</TD>
<TD WIDTH="9%" VALIGN="Top" ALIGN="Left">
<P>CH6103ME90
<P>2
</TD>
<TD WIDTH="9%" VALIGN="Top" ALIGN="Left">
<P>CAP CHIP 
<P>10U 
<P>16V(+-20%,
<P>X6S,0603)
</TD>
<TD WIDTH="9%" VALIGN="Top" ALIGN="Left">
<P>X6S
</TD>
<TD WIDTH="3%" VALIGN="Top" ALIGN="Right">
<P>2
</TD>
<TD WIDTH="9%" VALIGN="Top" ALIGN="Left">
<P>?
</TD>
<TD WIDTH="9%" VALIGN="Top" ALIGN="Left">
<P>?
</TD>
<TD WIDTH="18%" VALIGN="Top" ALIGN="Left">
<P>C163,C194
</TD>
<TD WIDTH="9%" VALIGN="Top" ALIGN="Left">
<P>?
</TD>
<TD WIDTH="9%" VALIGN="Top" ALIGN="Left">
<P>?
</TD>
<TD WIDTH="9%" VALIGN="Top" ALIGN="Left">
<P>?
</TD>
</TR>
<TR>
<TD WIDTH="5%" VALIGN="Top" ALIGN="Right">
<P>80
</TD>
<TD WIDTH="9%" VALIGN="Top" ALIGN="Left">
<P>CH6104KEA0
<P>0
</TD>
<TD WIDTH="9%" VALIGN="Top" ALIGN="Left">
<P>CAP CHIP 
<P>10U 
<P>25V(+-10%,
<P>X6S,0805,
<P>H1.25)
</TD>
<TD WIDTH="9%" VALIGN="Top" ALIGN="Left">
<P>X6S
</TD>
<TD WIDTH="3%" VALIGN="Top" ALIGN="Right">
<P>8
</TD>
<TD WIDTH="9%" VALIGN="Top" ALIGN="Left">
<P>?
</TD>
<TD WIDTH="9%" VALIGN="Top" ALIGN="Left">
<P>?
</TD>
<TD WIDTH="18%" VALIGN="Top" ALIGN="Left">
<P>PC237,PC242,PC248,
<P>PC251,PC252,PC261,
<P>PC262,PC307
</TD>
<TD WIDTH="9%" VALIGN="Top" ALIGN="Left">
<P>?
</TD>
<TD WIDTH="9%" VALIGN="Top" ALIGN="Left">
<P>?
</TD>
<TD WIDTH="9%" VALIGN="Top" ALIGN="Left">
<P>?
</TD>
</TR>
<TR>
<TD WIDTH="5%" VALIGN="Top" ALIGN="Right">
<P>81
</TD>
<TD WIDTH="9%" VALIGN="Top" ALIGN="Left">
<P>CH6221ME90
<P>0
</TD>
<TD WIDTH="9%" VALIGN="Top" ALIGN="Left">
<P>CAP CHIP 
<P>22U 
<P>6.3V(+-20%
<P>,X6S,0603)
</TD>
<TD WIDTH="9%" VALIGN="Top" ALIGN="Left">
<P>X6S
</TD>
<TD WIDTH="3%" VALIGN="Top" ALIGN="Right">
<P>7
</TD>
<TD WIDTH="9%" VALIGN="Top" ALIGN="Left">
<P>?
</TD>
<TD WIDTH="9%" VALIGN="Top" ALIGN="Left">
<P>?
</TD>
<TD WIDTH="18%" VALIGN="Top" ALIGN="Left">
<P>C42,C55,C118,C121,
<P>C123,C124,C126
</TD>
<TD WIDTH="9%" VALIGN="Top" ALIGN="Left">
<P>?
</TD>
<TD WIDTH="9%" VALIGN="Top" ALIGN="Left">
<P>?
</TD>
<TD WIDTH="9%" VALIGN="Top" ALIGN="Left">
<P>?
</TD>
</TR>
<TR>
<TD WIDTH="5%" VALIGN="Top" ALIGN="Right">
<P>82
</TD>
<TD WIDTH="9%" VALIGN="Top" ALIGN="Left">
<P>CH6221ME90
<P>0
</TD>
<TD WIDTH="9%" VALIGN="Top" ALIGN="Left">
<P>CAP CHIP 
<P>22U 
<P>6.3V(+-20%
<P>,X6S,0603)
</TD>
<TD WIDTH="9%" VALIGN="Top" ALIGN="Left">
<P>EMPTY
</TD>
<TD WIDTH="3%" VALIGN="Top" ALIGN="Right">
<P>1
</TD>
<TD WIDTH="9%" VALIGN="Top" ALIGN="Left">
<P>?
</TD>
<TD WIDTH="9%" VALIGN="Top" ALIGN="Left">
<P>?
</TD>
<TD WIDTH="18%" VALIGN="Top" ALIGN="Left">
<P>C232
</TD>
<TD WIDTH="9%" VALIGN="Top" ALIGN="Left">
<P>?
</TD>
<TD WIDTH="9%" VALIGN="Top" ALIGN="Left">
<P>?
</TD>
<TD WIDTH="9%" VALIGN="Top" ALIGN="Left">
<P>?
</TD>
</TR>
<TR>
<TD WIDTH="5%" VALIGN="Top" ALIGN="Right">
<P>83
</TD>
<TD WIDTH="9%" VALIGN="Top" ALIGN="Left">
<P>CH6222M990
<P>1
</TD>
<TD WIDTH="9%" VALIGN="Top" ALIGN="Left">
<P>CAP CHIP 
<P>22UF 
<P>10V(+-20%,
<P>X5R,0603)
</TD>
<TD WIDTH="9%" VALIGN="Top" ALIGN="Left">
<P>X5R
</TD>
<TD WIDTH="3%" VALIGN="Top" ALIGN="Right">
<P>7
</TD>
<TD WIDTH="9%" VALIGN="Top" ALIGN="Left">
<P>?
</TD>
<TD WIDTH="9%" VALIGN="Top" ALIGN="Left">
<P>?
</TD>
<TD WIDTH="18%" VALIGN="Top" ALIGN="Left">
<P>C113,C120,C125,C131,
<P>C132,C183,C184
</TD>
<TD WIDTH="9%" VALIGN="Top" ALIGN="Left">
<P>?
</TD>
<TD WIDTH="9%" VALIGN="Top" ALIGN="Left">
<P>?
</TD>
<TD WIDTH="9%" VALIGN="Top" ALIGN="Left">
<P>?
</TD>
</TR>
<TR>
<TD WIDTH="5%" VALIGN="Top" ALIGN="Right">
<P>84
</TD>
<TD WIDTH="9%" VALIGN="Top" ALIGN="Left">
<P>CH6222M990
<P>1
</TD>
<TD WIDTH="9%" VALIGN="Top" ALIGN="Left">
<P>CAP CHIP 
<P>22UF 
<P>10V(+-20%,
<P>X5R,0603)
</TD>
<TD WIDTH="9%" VALIGN="Top" ALIGN="Left">
<P>EMPTY
</TD>
<TD WIDTH="3%" VALIGN="Top" ALIGN="Right">
<P>1
</TD>
<TD WIDTH="9%" VALIGN="Top" ALIGN="Left">
<P>?
</TD>
<TD WIDTH="9%" VALIGN="Top" ALIGN="Left">
<P>?
</TD>
<TD WIDTH="18%" VALIGN="Top" ALIGN="Left">
<P>C234
</TD>
<TD WIDTH="9%" VALIGN="Top" ALIGN="Left">
<P>?
</TD>
<TD WIDTH="9%" VALIGN="Top" ALIGN="Left">
<P>?
</TD>
<TD WIDTH="9%" VALIGN="Top" ALIGN="Left">
<P>?
</TD>
</TR>
<TR>
<TD WIDTH="5%" VALIGN="Top" ALIGN="Right">
<P>85
</TD>
<TD WIDTH="9%" VALIGN="Top" ALIGN="Left">
<P>CH6222MEA0
<P>0
</TD>
<TD WIDTH="9%" VALIGN="Top" ALIGN="Left">
<P>CAP CHIP 
<P>22U 
<P>10V(+-20%,
<P>X6S,0805)
</TD>
<TD WIDTH="9%" VALIGN="Top" ALIGN="Left">
<P>X6S
</TD>
<TD WIDTH="3%" VALIGN="Top" ALIGN="Right">
<P>9
</TD>
<TD WIDTH="9%" VALIGN="Top" ALIGN="Left">
<P>?
</TD>
<TD WIDTH="9%" VALIGN="Top" ALIGN="Left">
<P>?
</TD>
<TD WIDTH="18%" VALIGN="Top" ALIGN="Left">
<P>C171,PC213,PC214,
<P>PC215,PC217,PC226,
<P>PC227,PC228,PC229
</TD>
<TD WIDTH="9%" VALIGN="Top" ALIGN="Left">
<P>?
</TD>
<TD WIDTH="9%" VALIGN="Top" ALIGN="Left">
<P>?
</TD>
<TD WIDTH="9%" VALIGN="Top" ALIGN="Left">
<P>?
</TD>
</TR>
<TR>
<TD WIDTH="5%" VALIGN="Top" ALIGN="Right">
<P>86
</TD>
<TD WIDTH="9%" VALIGN="Top" ALIGN="Left">
<P>CH6223MEA0
<P>1
</TD>
<TD WIDTH="9%" VALIGN="Top" ALIGN="Left">
<P>CAP CHIP 
<P>22UF 
<P>16V(+-20%,
<P>X6S,
<P>0805)MUR
</TD>
<TD WIDTH="9%" VALIGN="Top" ALIGN="Left">
<P>X6S
</TD>
<TD WIDTH="3%" VALIGN="Top" ALIGN="Right">
<P>5
</TD>
<TD WIDTH="9%" VALIGN="Top" ALIGN="Left">
<P>?
</TD>
<TD WIDTH="9%" VALIGN="Top" ALIGN="Left">
<P>?
</TD>
<TD WIDTH="18%" VALIGN="Top" ALIGN="Left">
<P>C265,PC206,PC207,
<P>PC218,PC219
</TD>
<TD WIDTH="9%" VALIGN="Top" ALIGN="Left">
<P>?
</TD>
<TD WIDTH="9%" VALIGN="Top" ALIGN="Left">
<P>?
</TD>
<TD WIDTH="9%" VALIGN="Top" ALIGN="Left">
<P>?
</TD>
</TR>
<TR>
<TD WIDTH="5%" VALIGN="Top" ALIGN="Right">
<P>87
</TD>
<TD WIDTH="9%" VALIGN="Top" ALIGN="Left">
<P>CH6224M9A0
<P>0
</TD>
<TD WIDTH="9%" VALIGN="Top" ALIGN="Left">
<P>CAP CHIP 
<P>22U 
<P>25V(+-20%,
<P>X5R,0805)
</TD>
<TD WIDTH="9%" VALIGN="Top" ALIGN="Left">
<P>X5R
</TD>
<TD WIDTH="3%" VALIGN="Top" ALIGN="Right">
<P>2
</TD>
<TD WIDTH="9%" VALIGN="Top" ALIGN="Left">
<P>?
</TD>
<TD WIDTH="9%" VALIGN="Top" ALIGN="Left">
<P>?
</TD>
<TD WIDTH="18%" VALIGN="Top" ALIGN="Left">
<P>C329,C330
</TD>
<TD WIDTH="9%" VALIGN="Top" ALIGN="Left">
<P>?
</TD>
<TD WIDTH="9%" VALIGN="Top" ALIGN="Left">
<P>?
</TD>
<TD WIDTH="9%" VALIGN="Top" ALIGN="Left">
<P>?
</TD>
</TR>
<TR>
<TD WIDTH="5%" VALIGN="Top" ALIGN="Right">
<P>88
</TD>
<TD WIDTH="9%" VALIGN="Top" ALIGN="Left">
<P>CH622KMEA0
<P>1
</TD>
<TD WIDTH="9%" VALIGN="Top" ALIGN="Left">
<P>CHIP0805
</TD>
<TD WIDTH="9%" VALIGN="Top" ALIGN="Left">
<P>X6S
</TD>
<TD WIDTH="3%" VALIGN="Top" ALIGN="Right">
<P>8
</TD>
<TD WIDTH="9%" VALIGN="Top" ALIGN="Left">
<P>?
</TD>
<TD WIDTH="9%" VALIGN="Top" ALIGN="Left">
<P>?
</TD>
<TD WIDTH="18%" VALIGN="Top" ALIGN="Left">
<P>PC256,PC257,PC258,
<P>PC259,PC267,PC268,
<P>PC269,PC270
</TD>
<TD WIDTH="9%" VALIGN="Top" ALIGN="Left">
<P>?
</TD>
<TD WIDTH="9%" VALIGN="Top" ALIGN="Left">
<P>Comp-Appro
<P>ve
</TD>
<TD WIDTH="9%" VALIGN="Top" ALIGN="Left">
<P>End of 
<P>Design
</TD>
</TR>
<TR>
<TD WIDTH="5%" VALIGN="Top" ALIGN="Right">
<P>89
</TD>
<TD WIDTH="9%" VALIGN="Top" ALIGN="Left">
<P>CH6472M920
<P>0
</TD>
<TD WIDTH="9%" VALIGN="Top" ALIGN="Left">
<P>CAP CHIP 
<P>47U 
<P>10V(+-20%,
<P>X5R,1206) 
<P> 
</TD>
<TD WIDTH="9%" VALIGN="Top" ALIGN="Left">
<P>X5R
</TD>
<TD WIDTH="3%" VALIGN="Top" ALIGN="Right">
<P>2
</TD>
<TD WIDTH="9%" VALIGN="Top" ALIGN="Left">
<P>?
</TD>
<TD WIDTH="9%" VALIGN="Top" ALIGN="Left">
<P>?
</TD>
<TD WIDTH="18%" VALIGN="Top" ALIGN="Left">
<P>C177,C327
</TD>
<TD WIDTH="9%" VALIGN="Top" ALIGN="Left">
<P>?
</TD>
<TD WIDTH="9%" VALIGN="Top" ALIGN="Left">
<P>Comp-Appro
<P>ve
</TD>
<TD WIDTH="9%" VALIGN="Top" ALIGN="Left">
<P>End of 
<P>Design
</TD>
</TR>
<TR>
<TD WIDTH="5%" VALIGN="Top" ALIGN="Right">
<P>90
</TD>
<TD WIDTH="9%" VALIGN="Top" ALIGN="Left">
<P>CS-5102JB0
<P>2
</TD>
<TD WIDTH="9%" VALIGN="Top" ALIGN="Left">
<P>RES CHIP 
<P>5.1 1/16W 
<P>+-5%(0402)
<P>EF
</TD>
<TD WIDTH="9%" VALIGN="Top" ALIGN="Left">
<P>CHIP
</TD>
<TD WIDTH="3%" VALIGN="Top" ALIGN="Right">
<P>2
</TD>
<TD WIDTH="9%" VALIGN="Top" ALIGN="Left">
<P>?
</TD>
<TD WIDTH="9%" VALIGN="Top" ALIGN="Left">
<P>?
</TD>
<TD WIDTH="18%" VALIGN="Top" ALIGN="Left">
<P>PR539,PR541
</TD>
<TD WIDTH="9%" VALIGN="Top" ALIGN="Left">
<P>?
</TD>
<TD WIDTH="9%" VALIGN="Top" ALIGN="Left">
<P>?
</TD>
<TD WIDTH="9%" VALIGN="Top" ALIGN="Left">
<P>?
</TD>
</TR>
<TR>
<TD WIDTH="5%" VALIGN="Top" ALIGN="Right">
<P>91
</TD>
<TD WIDTH="9%" VALIGN="Top" ALIGN="Left">
<P>CS00002JB1
<P>3
</TD>
<TD WIDTH="9%" VALIGN="Top" ALIGN="Left">
<P>RES CHIP 
<P>0 1/16W 
<P>+-5%(0402)
<P>EF
</TD>
<TD WIDTH="9%" VALIGN="Top" ALIGN="Left">
<P>CHIP
</TD>
<TD WIDTH="3%" VALIGN="Top" ALIGN="Right">
<P>152
</TD>
<TD WIDTH="9%" VALIGN="Top" ALIGN="Left">
<P>?
</TD>
<TD WIDTH="9%" VALIGN="Top" ALIGN="Left">
<P>?
</TD>
<TD WIDTH="18%" VALIGN="Top" ALIGN="Left">
<P>PR193,PR274,R2,R3,
<P>R18,R19,R20,R21,R24,
<P>R26,R30,R35,R39,R49,
<P>R51,R83,R86,R95,R97,
<P>R98,R99,R100,R105,
<P>R106,R109,R110,R113,
<P>R114,R134,R135,R141,
<P>R155,R184,R186,R198,
<P>R200,R207,R213,R216,
<P>R217,R218,R220,R231,
<P>R271,R272,R275,R276,
<P>R277,R279,R281,R282,
<P>R292,R293,R294,R300,
<P>R301,R302,R303,R304,
<P>R305,R307,R308,R315,
<P>R316,R317,R318,R320,
<P>R321,R322,R323,R379,
<P>R380,R381,R382,R384,
<P>R385,R386,R393,R397,
<P>R398,R399,R447,R451,
<P>R453,R454,R456,R457,
<P>R500,R503,R505,R519,
<P>R520,R525,R527,R528,
<P>R542,R564,R565,R566,
<P>R571,R572,R573,R574,
<P>R575,R576,R577,R578,
<P>R579,R587,R616,R626,
<P>R632,R634,R636,R637,
<P>R666,R668,R669,R670,
<P>R671,R672,R673,R674,
<P>R675,R676,R693,R695,
<P>R696,R697,R698,R700,
<P>R701,R702,R703,R707,
<P>R708,R720,R721,R722,
<P>R726,R728,R731,R732,
<P>R733,R734,R746,R747,
<P>R779,R783,R822,
<P>R5321,R5322
</TD>
<TD WIDTH="9%" VALIGN="Top" ALIGN="Left">
<P>?
</TD>
<TD WIDTH="9%" VALIGN="Top" ALIGN="Left">
<P>Comp-Appro
<P>ve
</TD>
<TD WIDTH="9%" VALIGN="Top" ALIGN="Left">
<P>End of 
<P>Design
</TD>
</TR>
<TR>
<TD WIDTH="5%" VALIGN="Top" ALIGN="Right">
<P>92
</TD>
<TD WIDTH="9%" VALIGN="Top" ALIGN="Left">
<P>CS00002JB1
<P>3
</TD>
<TD WIDTH="9%" VALIGN="Top" ALIGN="Left">
<P>RES CHIP 
<P>0 1/16W 
<P>+-5%(0402)
<P>EF
</TD>
<TD WIDTH="9%" VALIGN="Top" ALIGN="Left">
<P>EMPTY
</TD>
<TD WIDTH="3%" VALIGN="Top" ALIGN="Right">
<P>25
</TD>
<TD WIDTH="9%" VALIGN="Top" ALIGN="Left">
<P>?
</TD>
<TD WIDTH="9%" VALIGN="Top" ALIGN="Left">
<P>?
</TD>
<TD WIDTH="18%" VALIGN="Top" ALIGN="Left">
<P>PR205,PR275,R1,R63,
<P>R64,R154,R156,R208,
<P>R214,R232,R278,R280,
<P>R432,R450,R581,R711,
<P>R719,R748,R764,R780,
<P>R781,R782,R784,R898,
<P>R899
</TD>
<TD WIDTH="9%" VALIGN="Top" ALIGN="Left">
<P>?
</TD>
<TD WIDTH="9%" VALIGN="Top" ALIGN="Left">
<P>Comp-Appro
<P>ve
</TD>
<TD WIDTH="9%" VALIGN="Top" ALIGN="Left">
<P>End of 
<P>Design
</TD>
</TR>
<TR>
<TD WIDTH="5%" VALIGN="Top" ALIGN="Right">
<P>93
</TD>
<TD WIDTH="9%" VALIGN="Top" ALIGN="Left">
<P>CS00002JB3
<P>8
</TD>
<TD WIDTH="9%" VALIGN="Top" ALIGN="Left">
<P>RESISTOR 
<P>CHIP 0 
<P>1/16W 
<P>+-5%(0402)
</TD>
<TD WIDTH="9%" VALIGN="Top" ALIGN="Left">
<P>CHIP
</TD>
<TD WIDTH="3%" VALIGN="Top" ALIGN="Right">
<P>4
</TD>
<TD WIDTH="9%" VALIGN="Top" ALIGN="Left">
<P>?
</TD>
<TD WIDTH="9%" VALIGN="Top" ALIGN="Left">
<P>?
</TD>
<TD WIDTH="18%" VALIGN="Top" ALIGN="Left">
<P>R900,R901,R902,R903
</TD>
<TD WIDTH="9%" VALIGN="Top" ALIGN="Left">
<P>?
</TD>
<TD WIDTH="9%" VALIGN="Top" ALIGN="Left">
<P>Comp-Appro
<P>ve
</TD>
<TD WIDTH="9%" VALIGN="Top" ALIGN="Left">
<P>End of 
<P>Design
</TD>
</TR>
<TR>
<TD WIDTH="5%" VALIGN="Top" ALIGN="Right">
<P>94
</TD>
<TD WIDTH="9%" VALIGN="Top" ALIGN="Left">
<P>CS00003J91
<P>0
</TD>
<TD WIDTH="9%" VALIGN="Top" ALIGN="Left">
<P>RES CHIP 
<P>0 1/10W 
<P>+-5% 
<P>(0603)EF
</TD>
<TD WIDTH="9%" VALIGN="Top" ALIGN="Left">
<P>EMPTY
</TD>
<TD WIDTH="3%" VALIGN="Top" ALIGN="Right">
<P>3
</TD>
<TD WIDTH="9%" VALIGN="Top" ALIGN="Left">
<P>?
</TD>
<TD WIDTH="9%" VALIGN="Top" ALIGN="Left">
<P>?
</TD>
<TD WIDTH="18%" VALIGN="Top" ALIGN="Left">
<P>R27,R645,R646
</TD>
<TD WIDTH="9%" VALIGN="Top" ALIGN="Left">
<P>?
</TD>
<TD WIDTH="9%" VALIGN="Top" ALIGN="Left">
<P>Comp-Appro
<P>ve
</TD>
<TD WIDTH="9%" VALIGN="Top" ALIGN="Left">
<P>End of 
<P>Design
</TD>
</TR>
<TR>
<TD WIDTH="5%" VALIGN="Top" ALIGN="Right">
<P>95
</TD>
<TD WIDTH="9%" VALIGN="Top" ALIGN="Left">
<P>CS02202FB0
<P>2
</TD>
<TD WIDTH="9%" VALIGN="Top" ALIGN="Left">
<P>RES CHIP 
<P>22 1/16W 
<P>+-1%(0402)
<P>EF
</TD>
<TD WIDTH="9%" VALIGN="Top" ALIGN="Left">
<P>CHIP
</TD>
<TD WIDTH="3%" VALIGN="Top" ALIGN="Right">
<P>10
</TD>
<TD WIDTH="9%" VALIGN="Top" ALIGN="Left">
<P>?
</TD>
<TD WIDTH="9%" VALIGN="Top" ALIGN="Left">
<P>?
</TD>
<TD WIDTH="18%" VALIGN="Top" ALIGN="Left">
<P>R128,R129,R130,R131,
<P>R498,R499,R860,R861,
<P>R862,R863
</TD>
<TD WIDTH="9%" VALIGN="Top" ALIGN="Left">
<P>?
</TD>
<TD WIDTH="9%" VALIGN="Top" ALIGN="Left">
<P>Comp-Appro
<P>ve
</TD>
<TD WIDTH="9%" VALIGN="Top" ALIGN="Left">
<P>End of 
<P>Design
</TD>
</TR>
<TR>
<TD WIDTH="5%" VALIGN="Top" ALIGN="Right">
<P>96
</TD>
<TD WIDTH="9%" VALIGN="Top" ALIGN="Left">
<P>CS03302FB1
<P>9
</TD>
<TD WIDTH="9%" VALIGN="Top" ALIGN="Left">
<P>RES CHIP 
<P>33 1/16W 
<P>+-1%(0402)
</TD>
<TD WIDTH="9%" VALIGN="Top" ALIGN="Left">
<P>EMPTY
</TD>
<TD WIDTH="3%" VALIGN="Top" ALIGN="Right">
<P>11
</TD>
<TD WIDTH="9%" VALIGN="Top" ALIGN="Left">
<P>?
</TD>
<TD WIDTH="9%" VALIGN="Top" ALIGN="Left">
<P>?
</TD>
<TD WIDTH="18%" VALIGN="Top" ALIGN="Left">
<P>R48,R495,R532,R647,
<P>R648,R649,R650,R651,
<P>R652,R653,R654
</TD>
<TD WIDTH="9%" VALIGN="Top" ALIGN="Left">
<P>?
</TD>
<TD WIDTH="9%" VALIGN="Top" ALIGN="Left">
<P>Comp-Appro
<P>ve
</TD>
<TD WIDTH="9%" VALIGN="Top" ALIGN="Left">
<P>End of 
<P>Design
</TD>
</TR>
<TR>
<TD WIDTH="5%" VALIGN="Top" ALIGN="Right">
<P>97
</TD>
<TD WIDTH="9%" VALIGN="Top" ALIGN="Left">
<P>CS03302FB1
<P>9
</TD>
<TD WIDTH="9%" VALIGN="Top" ALIGN="Left">
<P>RES CHIP 
<P>33 1/16W 
<P>+-1%(0402)
</TD>
<TD WIDTH="9%" VALIGN="Top" ALIGN="Left">
<P>CHIP
</TD>
<TD WIDTH="3%" VALIGN="Top" ALIGN="Right">
<P>14
</TD>
<TD WIDTH="9%" VALIGN="Top" ALIGN="Left">
<P>?
</TD>
<TD WIDTH="9%" VALIGN="Top" ALIGN="Left">
<P>?
</TD>
<TD WIDTH="18%" VALIGN="Top" ALIGN="Left">
<P>R543,R544,R545,R546,
<P>R547,R548,R549,R550,
<P>R551,R552,R553,R554,
<P>R561,R562
</TD>
<TD WIDTH="9%" VALIGN="Top" ALIGN="Left">
<P>?
</TD>
<TD WIDTH="9%" VALIGN="Top" ALIGN="Left">
<P>Comp-Appro
<P>ve
</TD>
<TD WIDTH="9%" VALIGN="Top" ALIGN="Left">
<P>End of 
<P>Design
</TD>
</TR>
<TR>
<TD WIDTH="5%" VALIGN="Top" ALIGN="Right">
<P>98
</TD>
<TD WIDTH="9%" VALIGN="Top" ALIGN="Left">
<P>CS03322FB0
<P>3
</TD>
<TD WIDTH="9%" VALIGN="Top" ALIGN="Left">
<P>RES CHIP 
<P>33.2 
<P>1/16W 
<P>+-1%(0402)
<P>EF
</TD>
<TD WIDTH="9%" VALIGN="Top" ALIGN="Left">
<P>CHIP
</TD>
<TD WIDTH="3%" VALIGN="Top" ALIGN="Right">
<P>203
</TD>
<TD WIDTH="9%" VALIGN="Top" ALIGN="Left">
<P>?
</TD>
<TD WIDTH="9%" VALIGN="Top" ALIGN="Left">
<P>?
</TD>
<TD WIDTH="18%" VALIGN="Top" ALIGN="Left">
<P>R28,R29,R33,R36,R37,
<P>R46,R47,R60,R65,R71,
<P>R84,R85,R90,R93,
<P>R102,R104,R111,R112,
<P>R119,R120,R121,R122,
<P>R123,R132,R133,R137,
<P>R138,R139,R142,R143,
<P>R144,R146,R147,R148,
<P>R150,R151,R152,R153,
<P>R157,R158,R159,R160,
<P>R162,R165,R166,R168,
<P>R170,R171,R172,R173,
<P>R174,R175,R176,R177,
<P>R178,R179,R180,R181,
<P>R182,R183,R185,R187,
<P>R199,R201,R215,R221,
<P>R222,R223,R224,R225,
<P>R236,R237,R242,R243,
<P>R263,R270,R309,R310,
<P>R311,R394,R401,R402,
<P>R404,R405,R407,R420,
<P>R421,R423,R424,R425,
<P>R426,R427,R433,R434,
<P>R435,R436,R437,R439,
<P>R442,R443,R444,R445,
<P>R448,R449,R458,R459,
<P>R460,R461,R462,R463,
<P>R465,R466,R468,R469,
<P>R472,R473,R474,R475,
<P>R476,R477,R479,R480,
<P>R481,R482,R483,R484,
<P>R485,R486,R489,R494,
<P>R501,R509,R510,R511,
<P>R512,R513,R514,R515,
<P>R516,R517,R518,R522,
<P>R524,R526,R531,R533,
<P>R534,R535,R536,R537,
<P>R540,R541,R567,R570,
<P>R580,R582,R583,R584,
<P>R589,R590,R594,R635,
<P>R638,R639,R643,R644,
<P>R690,R691,R704,R705,
<P>R713,R715,R718,R724,
<P>R725,R750,R757,R759,
<P>R760,R761,R762,R763,
<P>R766,R767,R769,R773,
<P>R799,R801,R802,R807,
<P>R812,R813,R824,R825,
<P>R826,R833,R836,R837,
<P>R840,R841,R852,R859,
<P>R864
</TD>
<TD WIDTH="9%" VALIGN="Top" ALIGN="Left">
<P>?
</TD>
<TD WIDTH="9%" VALIGN="Top" ALIGN="Left">
<P>Comp-Appro
<P>ve
</TD>
<TD WIDTH="9%" VALIGN="Top" ALIGN="Left">
<P>End of 
<P>Design
</TD>
</TR>
<TR>
<TD WIDTH="5%" VALIGN="Top" ALIGN="Right">
<P>99
</TD>
<TD WIDTH="9%" VALIGN="Top" ALIGN="Left">
<P>CS03322FB0
<P>3
</TD>
<TD WIDTH="9%" VALIGN="Top" ALIGN="Left">
<P>RES CHIP 
<P>33.2 
<P>1/16W 
<P>+-1%(0402)
<P>EF
</TD>
<TD WIDTH="9%" VALIGN="Top" ALIGN="Left">
<P>EMPTY
</TD>
<TD WIDTH="3%" VALIGN="Top" ALIGN="Right">
<P>11
</TD>
<TD WIDTH="9%" VALIGN="Top" ALIGN="Left">
<P>?
</TD>
<TD WIDTH="9%" VALIGN="Top" ALIGN="Left">
<P>?
</TD>
<TD WIDTH="18%" VALIGN="Top" ALIGN="Left">
<P>R80,R96,R678,R679,
<P>R680,R681,R682,R688,
<P>R689,R752,R827
</TD>
<TD WIDTH="9%" VALIGN="Top" ALIGN="Left">
<P>?
</TD>
<TD WIDTH="9%" VALIGN="Top" ALIGN="Left">
<P>Comp-Appro
<P>ve
</TD>
<TD WIDTH="9%" VALIGN="Top" ALIGN="Left">
<P>End of 
<P>Design
</TD>
</TR>
<TR>
<TD WIDTH="5%" VALIGN="Top" ALIGN="Right">
<P>100
</TD>
<TD WIDTH="9%" VALIGN="Top" ALIGN="Left">
<P>CS04992FB0
<P>7
</TD>
<TD WIDTH="9%" VALIGN="Top" ALIGN="Left">
<P>RES CHIP 
<P>49.9 
<P>1/16W 
<P>+-1%(0402)
<P>EF
</TD>
<TD WIDTH="9%" VALIGN="Top" ALIGN="Left">
<P>CHIP
</TD>
<TD WIDTH="3%" VALIGN="Top" ALIGN="Right">
<P>6
</TD>
<TD WIDTH="9%" VALIGN="Top" ALIGN="Left">
<P>?
</TD>
<TD WIDTH="9%" VALIGN="Top" ALIGN="Left">
<P>?
</TD>
<TD WIDTH="18%" VALIGN="Top" ALIGN="Left">
<P>R108,R192,R283,R284,
<P>R409,R410
</TD>
<TD WIDTH="9%" VALIGN="Top" ALIGN="Left">
<P>?
</TD>
<TD WIDTH="9%" VALIGN="Top" ALIGN="Left">
<P>Comp-Appro
<P>ve
</TD>
<TD WIDTH="9%" VALIGN="Top" ALIGN="Left">
<P>End of 
<P>Design
</TD>
</TR>
<TR>
<TD WIDTH="5%" VALIGN="Top" ALIGN="Right">
<P>101
</TD>
<TD WIDTH="9%" VALIGN="Top" ALIGN="Left">
<P>CS06042FB0
<P>3
</TD>
<TD WIDTH="9%" VALIGN="Top" ALIGN="Left">
<P>RES CHIP 
<P>60.4 
<P>1/16W 
<P>+-1%(0402)
<P>EF
</TD>
<TD WIDTH="9%" VALIGN="Top" ALIGN="Left">
<P>CHIP
</TD>
<TD WIDTH="3%" VALIGN="Top" ALIGN="Right">
<P>2
</TD>
<TD WIDTH="9%" VALIGN="Top" ALIGN="Left">
<P>?
</TD>
<TD WIDTH="9%" VALIGN="Top" ALIGN="Left">
<P>?
</TD>
<TD WIDTH="18%" VALIGN="Top" ALIGN="Left">
<P>R7,R8
</TD>
<TD WIDTH="9%" VALIGN="Top" ALIGN="Left">
<P>?
</TD>
<TD WIDTH="9%" VALIGN="Top" ALIGN="Left">
<P>Comp-Appro
<P>ve
</TD>
<TD WIDTH="9%" VALIGN="Top" ALIGN="Left">
<P>End of 
<P>Design
</TD>
</TR>
<TR>
<TD WIDTH="5%" VALIGN="Top" ALIGN="Right">
<P>102
</TD>
<TD WIDTH="9%" VALIGN="Top" ALIGN="Left">
<P>CS11002FB0
<P>7
</TD>
<TD WIDTH="9%" VALIGN="Top" ALIGN="Left">
<P>RES CHIP 
<P>100 1/16W 
<P>+-1%(0402)
<P>EF
</TD>
<TD WIDTH="9%" VALIGN="Top" ALIGN="Left">
<P>EMPTY
</TD>
<TD WIDTH="3%" VALIGN="Top" ALIGN="Right">
<P>4
</TD>
<TD WIDTH="9%" VALIGN="Top" ALIGN="Left">
<P>?
</TD>
<TD WIDTH="9%" VALIGN="Top" ALIGN="Left">
<P>?
</TD>
<TD WIDTH="18%" VALIGN="Top" ALIGN="Left">
<P>R125,R743,R744,R745
</TD>
<TD WIDTH="9%" VALIGN="Top" ALIGN="Left">
<P>?
</TD>
<TD WIDTH="9%" VALIGN="Top" ALIGN="Left">
<P>Comp-Appro
<P>ve
</TD>
<TD WIDTH="9%" VALIGN="Top" ALIGN="Left">
<P>End of 
<P>Design
</TD>
</TR>
<TR>
<TD WIDTH="5%" VALIGN="Top" ALIGN="Right">
<P>103
</TD>
<TD WIDTH="9%" VALIGN="Top" ALIGN="Left">
<P>CS11002FB0
<P>7
</TD>
<TD WIDTH="9%" VALIGN="Top" ALIGN="Left">
<P>RES CHIP 
<P>100 1/16W 
<P>+-1%(0402)
<P>EF
</TD>
<TD WIDTH="9%" VALIGN="Top" ALIGN="Left">
<P>CHIP
</TD>
<TD WIDTH="3%" VALIGN="Top" ALIGN="Right">
<P>8
</TD>
<TD WIDTH="9%" VALIGN="Top" ALIGN="Left">
<P>?
</TD>
<TD WIDTH="9%" VALIGN="Top" ALIGN="Left">
<P>?
</TD>
<TD WIDTH="18%" VALIGN="Top" ALIGN="Left">
<P>R94,R411,R412,R413,
<P>R431,R506,R507,R694
</TD>
<TD WIDTH="9%" VALIGN="Top" ALIGN="Left">
<P>?
</TD>
<TD WIDTH="9%" VALIGN="Top" ALIGN="Left">
<P>Comp-Appro
<P>ve
</TD>
<TD WIDTH="9%" VALIGN="Top" ALIGN="Left">
<P>End of 
<P>Design
</TD>
</TR>
<TR>
<TD WIDTH="5%" VALIGN="Top" ALIGN="Right">
<P>104
</TD>
<TD WIDTH="9%" VALIGN="Top" ALIGN="Left">
<P>CS11202FB0
<P>2
</TD>
<TD WIDTH="9%" VALIGN="Top" ALIGN="Left">
<P>RES CHIP 
<P>120 1/16W 
<P>+-1%(0402)
<P>EF
</TD>
<TD WIDTH="9%" VALIGN="Top" ALIGN="Left">
<P>CHIP
</TD>
<TD WIDTH="3%" VALIGN="Top" ALIGN="Right">
<P>48
</TD>
<TD WIDTH="9%" VALIGN="Top" ALIGN="Left">
<P>?
</TD>
<TD WIDTH="9%" VALIGN="Top" ALIGN="Left">
<P>?
</TD>
<TD WIDTH="18%" VALIGN="Top" ALIGN="Left">
<P>R326,R327,R328,R329,
<P>R330,R331,R332,R333,
<P>R334,R335,R336,R337,
<P>R338,R339,R340,R341,
<P>R342,R343,R344,R345,
<P>R346,R347,R348,R349,
<P>R351,R352,R353,R354,
<P>R355,R356,R357,R358,
<P>R359,R360,R361,R362,
<P>R363,R364,R365,R366,
<P>R367,R368,R369,R370,
<P>R371,R372,R373,R374
</TD>
<TD WIDTH="9%" VALIGN="Top" ALIGN="Left">
<P>?
</TD>
<TD WIDTH="9%" VALIGN="Top" ALIGN="Left">
<P>Comp-Appro
<P>ve
</TD>
<TD WIDTH="9%" VALIGN="Top" ALIGN="Left">
<P>End of 
<P>Design
</TD>
</TR>
<TR>
<TD WIDTH="5%" VALIGN="Top" ALIGN="Right">
<P>105
</TD>
<TD WIDTH="9%" VALIGN="Top" ALIGN="Left">
<P>CS11202FB0
<P>2
</TD>
<TD WIDTH="9%" VALIGN="Top" ALIGN="Left">
<P>RES CHIP 
<P>120 1/16W 
<P>+-1%(0402)
<P>EF
</TD>
<TD WIDTH="9%" VALIGN="Top" ALIGN="Left">
<P>EMPTY
</TD>
<TD WIDTH="3%" VALIGN="Top" ALIGN="Right">
<P>2
</TD>
<TD WIDTH="9%" VALIGN="Top" ALIGN="Left">
<P>?
</TD>
<TD WIDTH="9%" VALIGN="Top" ALIGN="Left">
<P>?
</TD>
<TD WIDTH="18%" VALIGN="Top" ALIGN="Left">
<P>R350,R375
</TD>
<TD WIDTH="9%" VALIGN="Top" ALIGN="Left">
<P>?
</TD>
<TD WIDTH="9%" VALIGN="Top" ALIGN="Left">
<P>Comp-Appro
<P>ve
</TD>
<TD WIDTH="9%" VALIGN="Top" ALIGN="Left">
<P>End of 
<P>Design
</TD>
</TR>
<TR>
<TD WIDTH="5%" VALIGN="Top" ALIGN="Right">
<P>106
</TD>
<TD WIDTH="9%" VALIGN="Top" ALIGN="Left">
<P>CS11502FB0
<P>7
</TD>
<TD WIDTH="9%" VALIGN="Top" ALIGN="Left">
<P>RES CHIP 
<P>150 1/16W 
<P>+-1%(0402)
<P>EF
</TD>
<TD WIDTH="9%" VALIGN="Top" ALIGN="Left">
<P>CHIP
</TD>
<TD WIDTH="3%" VALIGN="Top" ALIGN="Right">
<P>6
</TD>
<TD WIDTH="9%" VALIGN="Top" ALIGN="Left">
<P>?
</TD>
<TD WIDTH="9%" VALIGN="Top" ALIGN="Left">
<P>?
</TD>
<TD WIDTH="18%" VALIGN="Top" ALIGN="Left">
<P>R22,R23,R25,R87,R88,
<P>R89
</TD>
<TD WIDTH="9%" VALIGN="Top" ALIGN="Left">
<P>?
</TD>
<TD WIDTH="9%" VALIGN="Top" ALIGN="Left">
<P>Comp-Appro
<P>ve
</TD>
<TD WIDTH="9%" VALIGN="Top" ALIGN="Left">
<P>End of 
<P>Design
</TD>
</TR>
<TR>
<TD WIDTH="5%" VALIGN="Top" ALIGN="Right">
<P>107
</TD>
<TD WIDTH="9%" VALIGN="Top" ALIGN="Left">
<P>CS12202FB0
<P>4
</TD>
<TD WIDTH="9%" VALIGN="Top" ALIGN="Left">
<P>RES CHIP 
<P>220 1/16W 
<P>+-1%(0402)
<P>EF
</TD>
<TD WIDTH="9%" VALIGN="Top" ALIGN="Left">
<P>CHIP
</TD>
<TD WIDTH="3%" VALIGN="Top" ALIGN="Right">
<P>3
</TD>
<TD WIDTH="9%" VALIGN="Top" ALIGN="Left">
<P>?
</TD>
<TD WIDTH="9%" VALIGN="Top" ALIGN="Left">
<P>?
</TD>
<TD WIDTH="18%" VALIGN="Top" ALIGN="Left">
<P>R43,R568,R569
</TD>
<TD WIDTH="9%" VALIGN="Top" ALIGN="Left">
<P>?
</TD>
<TD WIDTH="9%" VALIGN="Top" ALIGN="Left">
<P>?
</TD>
<TD WIDTH="9%" VALIGN="Top" ALIGN="Left">
<P>?
</TD>
</TR>
<TR>
<TD WIDTH="5%" VALIGN="Top" ALIGN="Right">
<P>108
</TD>
<TD WIDTH="9%" VALIGN="Top" ALIGN="Left">
<P>CS12402FB0
<P>1
</TD>
<TD WIDTH="9%" VALIGN="Top" ALIGN="Left">
<P>RES CHIP 
<P>240 1/16W 
<P>+-1%(0402)
<P>EF
</TD>
<TD WIDTH="9%" VALIGN="Top" ALIGN="Left">
<P>CHIP
</TD>
<TD WIDTH="3%" VALIGN="Top" ALIGN="Right">
<P>2
</TD>
<TD WIDTH="9%" VALIGN="Top" ALIGN="Left">
<P>?
</TD>
<TD WIDTH="9%" VALIGN="Top" ALIGN="Left">
<P>?
</TD>
<TD WIDTH="18%" VALIGN="Top" ALIGN="Left">
<P>R6,R127
</TD>
<TD WIDTH="9%" VALIGN="Top" ALIGN="Left">
<P>?
</TD>
<TD WIDTH="9%" VALIGN="Top" ALIGN="Left">
<P>Comp-Appro
<P>ve
</TD>
<TD WIDTH="9%" VALIGN="Top" ALIGN="Left">
<P>End of 
<P>Design
</TD>
</TR>
<TR>
<TD WIDTH="5%" VALIGN="Top" ALIGN="Right">
<P>109
</TD>
<TD WIDTH="9%" VALIGN="Top" ALIGN="Left">
<P>CS13302FB0
<P>0
</TD>
<TD WIDTH="9%" VALIGN="Top" ALIGN="Left">
<P>RES CHIP 
<P>330 1/16W 
<P>+-1%(0402)
<P>EF
</TD>
<TD WIDTH="9%" VALIGN="Top" ALIGN="Left">
<P>CHIP
</TD>
<TD WIDTH="3%" VALIGN="Top" ALIGN="Right">
<P>1
</TD>
<TD WIDTH="9%" VALIGN="Top" ALIGN="Left">
<P>?
</TD>
<TD WIDTH="9%" VALIGN="Top" ALIGN="Left">
<P>?
</TD>
<TD WIDTH="18%" VALIGN="Top" ALIGN="Left">
<P>R167
</TD>
<TD WIDTH="9%" VALIGN="Top" ALIGN="Left">
<P>?
</TD>
<TD WIDTH="9%" VALIGN="Top" ALIGN="Left">
<P>Comp-Appro
<P>ve
</TD>
<TD WIDTH="9%" VALIGN="Top" ALIGN="Left">
<P>End of 
<P>Design
</TD>
</TR>
<TR>
<TD WIDTH="5%" VALIGN="Top" ALIGN="Right">
<P>110
</TD>
<TD WIDTH="9%" VALIGN="Top" ALIGN="Left">
<P>CS14992FB0
<P>6
</TD>
<TD WIDTH="9%" VALIGN="Top" ALIGN="Left">
<P>RES CHIP 
<P>499 1/16W 
<P>+-1%(0402)
<P>EF
</TD>
<TD WIDTH="9%" VALIGN="Top" ALIGN="Left">
<P>CHIP
</TD>
<TD WIDTH="3%" VALIGN="Top" ALIGN="Right">
<P>1
</TD>
<TD WIDTH="9%" VALIGN="Top" ALIGN="Left">
<P>?
</TD>
<TD WIDTH="9%" VALIGN="Top" ALIGN="Left">
<P>?
</TD>
<TD WIDTH="18%" VALIGN="Top" ALIGN="Left">
<P>R287
</TD>
<TD WIDTH="9%" VALIGN="Top" ALIGN="Left">
<P>?
</TD>
<TD WIDTH="9%" VALIGN="Top" ALIGN="Left">
<P>Comp-Appro
<P>ve
</TD>
<TD WIDTH="9%" VALIGN="Top" ALIGN="Left">
<P>End of 
<P>Design
</TD>
</TR>
<TR>
<TD WIDTH="5%" VALIGN="Top" ALIGN="Right">
<P>111
</TD>
<TD WIDTH="9%" VALIGN="Top" ALIGN="Left">
<P>CS16652FB0
<P>0
</TD>
<TD WIDTH="9%" VALIGN="Top" ALIGN="Left">
<P>RES CHIP 
<P>665 1/16W 
<P>+-1%(0402)
<P>EF
</TD>
<TD WIDTH="9%" VALIGN="Top" ALIGN="Left">
<P>CHIP
</TD>
<TD WIDTH="3%" VALIGN="Top" ALIGN="Right">
<P>1
</TD>
<TD WIDTH="9%" VALIGN="Top" ALIGN="Left">
<P>?
</TD>
<TD WIDTH="9%" VALIGN="Top" ALIGN="Left">
<P>?
</TD>
<TD WIDTH="18%" VALIGN="Top" ALIGN="Left">
<P>R793
</TD>
<TD WIDTH="9%" VALIGN="Top" ALIGN="Left">
<P>?
</TD>
<TD WIDTH="9%" VALIGN="Top" ALIGN="Left">
<P>Comp-Appro
<P>ve
</TD>
<TD WIDTH="9%" VALIGN="Top" ALIGN="Left">
<P>End of 
<P>Design
</TD>
</TR>
<TR>
<TD WIDTH="5%" VALIGN="Top" ALIGN="Right">
<P>112
</TD>
<TD WIDTH="9%" VALIGN="Top" ALIGN="Left">
<P>CS17502FB0
<P>3
</TD>
<TD WIDTH="9%" VALIGN="Top" ALIGN="Left">
<P>RES CHIP 
<P>750 1/16W 
<P>+-1%(0402)
<P>EF
</TD>
<TD WIDTH="9%" VALIGN="Top" ALIGN="Left">
<P>CHIP
</TD>
<TD WIDTH="3%" VALIGN="Top" ALIGN="Right">
<P>8
</TD>
<TD WIDTH="9%" VALIGN="Top" ALIGN="Left">
<P>?
</TD>
<TD WIDTH="9%" VALIGN="Top" ALIGN="Left">
<P>?
</TD>
<TD WIDTH="18%" VALIGN="Top" ALIGN="Left">
<P>R597,R598,R599,R600,
<P>R601,R602,R603,R604
</TD>
<TD WIDTH="9%" VALIGN="Top" ALIGN="Left">
<P>?
</TD>
<TD WIDTH="9%" VALIGN="Top" ALIGN="Left">
<P>Comp-Appro
<P>ve
</TD>
<TD WIDTH="9%" VALIGN="Top" ALIGN="Left">
<P>End of 
<P>Design
</TD>
</TR>
<TR>
<TD WIDTH="5%" VALIGN="Top" ALIGN="Right">
<P>113
</TD>
<TD WIDTH="9%" VALIGN="Top" ALIGN="Left">
<P>CS21002FB0
<P>6
</TD>
<TD WIDTH="9%" VALIGN="Top" ALIGN="Left">
<P>RES CHIP 
<P>1K 1/16W 
<P>+-1%(0402)
<P>EF
</TD>
<TD WIDTH="9%" VALIGN="Top" ALIGN="Left">
<P>CHIP
</TD>
<TD WIDTH="3%" VALIGN="Top" ALIGN="Right">
<P>21
</TD>
<TD WIDTH="9%" VALIGN="Top" ALIGN="Left">
<P>?
</TD>
<TD WIDTH="9%" VALIGN="Top" ALIGN="Left">
<P>?
</TD>
<TD WIDTH="18%" VALIGN="Top" ALIGN="Left">
<P>R4,R5,R15,R188,R189,
<P>R190,R191,R194,R195,
<P>R196,R197,R210,R324,
<P>R325,R419,R735,R736,
<P>R775,R795,R796,R5324
</TD>
<TD WIDTH="9%" VALIGN="Top" ALIGN="Left">
<P>?
</TD>
<TD WIDTH="9%" VALIGN="Top" ALIGN="Left">
<P>Comp-Appro
<P>ve
</TD>
<TD WIDTH="9%" VALIGN="Top" ALIGN="Left">
<P>End of 
<P>Design
</TD>
</TR>
<TR>
<TD WIDTH="5%" VALIGN="Top" ALIGN="Right">
<P>114
</TD>
<TD WIDTH="9%" VALIGN="Top" ALIGN="Left">
<P>CS21002FB0
<P>6
</TD>
<TD WIDTH="9%" VALIGN="Top" ALIGN="Left">
<P>RES CHIP 
<P>1K 1/16W 
<P>+-1%(0402)
<P>EF
</TD>
<TD WIDTH="9%" VALIGN="Top" ALIGN="Left">
<P>EMPTY
</TD>
<TD WIDTH="3%" VALIGN="Top" ALIGN="Right">
<P>5
</TD>
<TD WIDTH="9%" VALIGN="Top" ALIGN="Left">
<P>?
</TD>
<TD WIDTH="9%" VALIGN="Top" ALIGN="Left">
<P>?
</TD>
<TD WIDTH="18%" VALIGN="Top" ALIGN="Left">
<P>R53,R73,R77,R417,
<P>R633
</TD>
<TD WIDTH="9%" VALIGN="Top" ALIGN="Left">
<P>?
</TD>
<TD WIDTH="9%" VALIGN="Top" ALIGN="Left">
<P>Comp-Appro
<P>ve
</TD>
<TD WIDTH="9%" VALIGN="Top" ALIGN="Left">
<P>End of 
<P>Design
</TD>
</TR>
<TR>
<TD WIDTH="5%" VALIGN="Top" ALIGN="Right">
<P>115
</TD>
<TD WIDTH="9%" VALIGN="Top" ALIGN="Left">
<P>CS21002FB2
<P>4
</TD>
<TD WIDTH="9%" VALIGN="Top" ALIGN="Left">
<P>RES CHIP 
<P>1K 1/16W 
<P>+-1% 
<P>(0402)
</TD>
<TD WIDTH="9%" VALIGN="Top" ALIGN="Left">
<P>EMPTY
</TD>
<TD WIDTH="3%" VALIGN="Top" ALIGN="Right">
<P>4
</TD>
<TD WIDTH="9%" VALIGN="Top" ALIGN="Left">
<P>?
</TD>
<TD WIDTH="9%" VALIGN="Top" ALIGN="Left">
<P>?
</TD>
<TD WIDTH="18%" VALIGN="Top" ALIGN="Left">
<P>R664,R665,R684,R685
</TD>
<TD WIDTH="9%" VALIGN="Top" ALIGN="Left">
<P>?
</TD>
<TD WIDTH="9%" VALIGN="Top" ALIGN="Left">
<P>Comp-Appro
<P>ve
</TD>
<TD WIDTH="9%" VALIGN="Top" ALIGN="Left">
<P>End of 
<P>Design
</TD>
</TR>
<TR>
<TD WIDTH="5%" VALIGN="Top" ALIGN="Right">
<P>116
</TD>
<TD WIDTH="9%" VALIGN="Top" ALIGN="Left">
<P>CS21692FB0
<P>4
</TD>
<TD WIDTH="9%" VALIGN="Top" ALIGN="Left">
<P>RES CHIP 
<P>1.69K 
<P>1/16W 
<P>+-1%(0402)
<P>EF
</TD>
<TD WIDTH="9%" VALIGN="Top" ALIGN="Left">
<P>CHIP
</TD>
<TD WIDTH="3%" VALIGN="Top" ALIGN="Right">
<P>1
</TD>
<TD WIDTH="9%" VALIGN="Top" ALIGN="Left">
<P>?
</TD>
<TD WIDTH="9%" VALIGN="Top" ALIGN="Left">
<P>?
</TD>
<TD WIDTH="18%" VALIGN="Top" ALIGN="Left">
<P>R791
</TD>
<TD WIDTH="9%" VALIGN="Top" ALIGN="Left">
<P>?
</TD>
<TD WIDTH="9%" VALIGN="Top" ALIGN="Left">
<P>Comp-Appro
<P>ve
</TD>
<TD WIDTH="9%" VALIGN="Top" ALIGN="Left">
<P>End of 
<P>Design
</TD>
</TR>
<TR>
<TD WIDTH="5%" VALIGN="Top" ALIGN="Right">
<P>117
</TD>
<TD WIDTH="9%" VALIGN="Top" ALIGN="Left">
<P>CS22002FB0
<P>7
</TD>
<TD WIDTH="9%" VALIGN="Top" ALIGN="Left">
<P>RES CHIP 
<P>2K 1/16W 
<P>+-1%(0402)
<P>EF
</TD>
<TD WIDTH="9%" VALIGN="Top" ALIGN="Left">
<P>CHIP
</TD>
<TD WIDTH="3%" VALIGN="Top" ALIGN="Right">
<P>16
</TD>
<TD WIDTH="9%" VALIGN="Top" ALIGN="Left">
<P>?
</TD>
<TD WIDTH="9%" VALIGN="Top" ALIGN="Left">
<P>?
</TD>
<TD WIDTH="18%" VALIGN="Top" ALIGN="Left">
<P>R74,R75,R76,R78,R79,
<P>R82,R124,R467,R714,
<P>R751,R786,R788,R790,
<P>R792,R794,R798
</TD>
<TD WIDTH="9%" VALIGN="Top" ALIGN="Left">
<P>?
</TD>
<TD WIDTH="9%" VALIGN="Top" ALIGN="Left">
<P>Comp-Appro
<P>ve
</TD>
<TD WIDTH="9%" VALIGN="Top" ALIGN="Left">
<P>End of 
<P>Design
</TD>
</TR>
<TR>
<TD WIDTH="5%" VALIGN="Top" ALIGN="Right">
<P>118
</TD>
<TD WIDTH="9%" VALIGN="Top" ALIGN="Left">
<P>CS22002FB0
<P>7
</TD>
<TD WIDTH="9%" VALIGN="Top" ALIGN="Left">
<P>RES CHIP 
<P>2K 1/16W 
<P>+-1%(0402)
<P>EF
</TD>
<TD WIDTH="9%" VALIGN="Top" ALIGN="Left">
<P>EMPTY
</TD>
<TD WIDTH="3%" VALIGN="Top" ALIGN="Right">
<P>1
</TD>
<TD WIDTH="9%" VALIGN="Top" ALIGN="Left">
<P>?
</TD>
<TD WIDTH="9%" VALIGN="Top" ALIGN="Left">
<P>?
</TD>
<TD WIDTH="18%" VALIGN="Top" ALIGN="Left">
<P>R40
</TD>
<TD WIDTH="9%" VALIGN="Top" ALIGN="Left">
<P>?
</TD>
<TD WIDTH="9%" VALIGN="Top" ALIGN="Left">
<P>Comp-Appro
<P>ve
</TD>
<TD WIDTH="9%" VALIGN="Top" ALIGN="Left">
<P>End of 
<P>Design
</TD>
</TR>
<TR>
<TD WIDTH="5%" VALIGN="Top" ALIGN="Right">
<P>119
</TD>
<TD WIDTH="9%" VALIGN="Top" ALIGN="Left">
<P>CS22202JB0
<P>7
</TD>
<TD WIDTH="9%" VALIGN="Top" ALIGN="Left">
<P>RES CHIP 
<P>2.2K 
<P>1/16W 
<P>+-5%(0402)
<P>EF
</TD>
<TD WIDTH="9%" VALIGN="Top" ALIGN="Left">
<P>CHIP
</TD>
<TD WIDTH="3%" VALIGN="Top" ALIGN="Right">
<P>2
</TD>
<TD WIDTH="9%" VALIGN="Top" ALIGN="Left">
<P>?
</TD>
<TD WIDTH="9%" VALIGN="Top" ALIGN="Left">
<P>?
</TD>
<TD WIDTH="18%" VALIGN="Top" ALIGN="Left">
<P>R91,R92
</TD>
<TD WIDTH="9%" VALIGN="Top" ALIGN="Left">
<P>?
</TD>
<TD WIDTH="9%" VALIGN="Top" ALIGN="Left">
<P>Comp-Appro
<P>ve
</TD>
<TD WIDTH="9%" VALIGN="Top" ALIGN="Left">
<P>End of 
<P>Design
</TD>
</TR>
<TR>
<TD WIDTH="5%" VALIGN="Top" ALIGN="Right">
<P>120
</TD>
<TD WIDTH="9%" VALIGN="Top" ALIGN="Left">
<P>CS22212FB0
<P>6
</TD>
<TD WIDTH="9%" VALIGN="Top" ALIGN="Left">
<P>RES CHIP 
<P>2.21K 
<P>1/16W 
<P>+-1%(0402)
<P>EF
</TD>
<TD WIDTH="9%" VALIGN="Top" ALIGN="Left">
<P>EMPTY
</TD>
<TD WIDTH="3%" VALIGN="Top" ALIGN="Right">
<P>2
</TD>
<TD WIDTH="9%" VALIGN="Top" ALIGN="Left">
<P>?
</TD>
<TD WIDTH="9%" VALIGN="Top" ALIGN="Left">
<P>?
</TD>
<TD WIDTH="18%" VALIGN="Top" ALIGN="Left">
<P>R16,R17
</TD>
<TD WIDTH="9%" VALIGN="Top" ALIGN="Left">
<P>?
</TD>
<TD WIDTH="9%" VALIGN="Top" ALIGN="Left">
<P>Comp-Appro
<P>ve
</TD>
<TD WIDTH="9%" VALIGN="Top" ALIGN="Left">
<P>End of 
<P>Design
</TD>
</TR>
<TR>
<TD WIDTH="5%" VALIGN="Top" ALIGN="Right">
<P>121
</TD>
<TD WIDTH="9%" VALIGN="Top" ALIGN="Left">
<P>CS22742FB0
<P>5
</TD>
<TD WIDTH="9%" VALIGN="Top" ALIGN="Left">
<P>RES CHIP 
<P>2.74K 
<P>1/16W 
<P>+-1%(0402)
<P>EF
</TD>
<TD WIDTH="9%" VALIGN="Top" ALIGN="Left">
<P>CHIP
</TD>
<TD WIDTH="3%" VALIGN="Top" ALIGN="Right">
<P>1
</TD>
<TD WIDTH="9%" VALIGN="Top" ALIGN="Left">
<P>?
</TD>
<TD WIDTH="9%" VALIGN="Top" ALIGN="Left">
<P>?
</TD>
<TD WIDTH="18%" VALIGN="Top" ALIGN="Left">
<P>R235
</TD>
<TD WIDTH="9%" VALIGN="Top" ALIGN="Left">
<P>?
</TD>
<TD WIDTH="9%" VALIGN="Top" ALIGN="Left">
<P>Comp-Appro
<P>ve
</TD>
<TD WIDTH="9%" VALIGN="Top" ALIGN="Left">
<P>End of 
<P>Design
</TD>
</TR>
<TR>
<TD WIDTH="5%" VALIGN="Top" ALIGN="Right">
<P>122
</TD>
<TD WIDTH="9%" VALIGN="Top" ALIGN="Left">
<P>CS22872FB0
<P>3
</TD>
<TD WIDTH="9%" VALIGN="Top" ALIGN="Left">
<P>RES CHIP 
<P>2.87K 
<P>1/16W 
<P>+-1%(0402)
<P>EF
</TD>
<TD WIDTH="9%" VALIGN="Top" ALIGN="Left">
<P>CHIP
</TD>
<TD WIDTH="3%" VALIGN="Top" ALIGN="Right">
<P>2
</TD>
<TD WIDTH="9%" VALIGN="Top" ALIGN="Left">
<P>?
</TD>
<TD WIDTH="9%" VALIGN="Top" ALIGN="Left">
<P>?
</TD>
<TD WIDTH="18%" VALIGN="Top" ALIGN="Left">
<P>R789,R797
</TD>
<TD WIDTH="9%" VALIGN="Top" ALIGN="Left">
<P>?
</TD>
<TD WIDTH="9%" VALIGN="Top" ALIGN="Left">
<P>Comp-Appro
<P>ve
</TD>
<TD WIDTH="9%" VALIGN="Top" ALIGN="Left">
<P>End of 
<P>Design
</TD>
</TR>
<TR>
<TD WIDTH="5%" VALIGN="Top" ALIGN="Right">
<P>123
</TD>
<TD WIDTH="9%" VALIGN="Top" ALIGN="Left">
<P>CS24702FB0
<P>6
</TD>
<TD WIDTH="9%" VALIGN="Top" ALIGN="Left">
<P>RES CHIP 
<P>4.7K 
<P>1/16W 
<P>+-1%(0402)
<P>EF
</TD>
<TD WIDTH="9%" VALIGN="Top" ALIGN="Left">
<P>CHIP
</TD>
<TD WIDTH="3%" VALIGN="Top" ALIGN="Right">
<P>125
</TD>
<TD WIDTH="9%" VALIGN="Top" ALIGN="Left">
<P>?
</TD>
<TD WIDTH="9%" VALIGN="Top" ALIGN="Left">
<P>?
</TD>
<TD WIDTH="18%" VALIGN="Top" ALIGN="Left">
<P>R9,R31,R32,R38,R42,
<P>R44,R45,R52,R55,R56,
<P>R57,R58,R61,R62,R67,
<P>R68,R69,R70,R72,R81,
<P>R101,R103,R115,R116,
<P>R117,R140,R145,R149,
<P>R161,R163,R169,R212,
<P>R238,R239,R240,R241,
<P>R244,R245,R246,R247,
<P>R248,R249,R250,R251,
<P>R252,R253,R254,R255,
<P>R256,R257,R258,R259,
<P>R260,R261,R262,R264,
<P>R265,R268,R269,R285,
<P>R291,R298,R299,R319,
<P>R376,R387,R389,R400,
<P>R416,R422,R428,R429,
<P>R430,R438,R446,R452,
<P>R488,R490,R492,R521,
<P>R563,R586,R588,R591,
<P>R606,R607,R608,R609,
<P>R610,R611,R612,R613,
<P>R615,R617,R621,R622,
<P>R624,R625,R627,R667,
<P>R683,R692,R706,R717,
<P>R730,R738,R739,R740,
<P>R741,R749,R758,R765,
<P>R774,R805,R806,R816,
<P>R835,R842,R843,R844,
<P>R848,R851,R5323,
<P>R5340,R5375
</TD>
<TD WIDTH="9%" VALIGN="Top" ALIGN="Left">
<P>?
</TD>
<TD WIDTH="9%" VALIGN="Top" ALIGN="Left">
<P>Comp-Appro
<P>ve
</TD>
<TD WIDTH="9%" VALIGN="Top" ALIGN="Left">
<P>End of 
<P>Design
</TD>
</TR>
<TR>
<TD WIDTH="5%" VALIGN="Top" ALIGN="Right">
<P>124
</TD>
<TD WIDTH="9%" VALIGN="Top" ALIGN="Left">
<P>CS24702FB0
<P>6
</TD>
<TD WIDTH="9%" VALIGN="Top" ALIGN="Left">
<P>RES CHIP 
<P>4.7K 
<P>1/16W 
<P>+-1%(0402)
<P>EF
</TD>
<TD WIDTH="9%" VALIGN="Top" ALIGN="Left">
<P>EMPTY
</TD>
<TD WIDTH="3%" VALIGN="Top" ALIGN="Right">
<P>33
</TD>
<TD WIDTH="9%" VALIGN="Top" ALIGN="Left">
<P>?
</TD>
<TD WIDTH="9%" VALIGN="Top" ALIGN="Left">
<P>?
</TD>
<TD WIDTH="18%" VALIGN="Top" ALIGN="Left">
<P>R12,R13,R14,R34,
<P>R107,R229,R266,R267,
<P>R286,R388,R390,R418,
<P>R487,R491,R496,R593,
<P>R595,R596,R605,R623,
<P>R640,R641,R699,R737,
<P>R742,R753,R754,R770,
<P>R821,R828,R845,R846,
<P>R870
</TD>
<TD WIDTH="9%" VALIGN="Top" ALIGN="Left">
<P>?
</TD>
<TD WIDTH="9%" VALIGN="Top" ALIGN="Left">
<P>Comp-Appro
<P>ve
</TD>
<TD WIDTH="9%" VALIGN="Top" ALIGN="Left">
<P>End of 
<P>Design
</TD>
</TR>
<TR>
<TD WIDTH="5%" VALIGN="Top" ALIGN="Right">
<P>125
</TD>
<TD WIDTH="9%" VALIGN="Top" ALIGN="Left">
<P>CS24702FB1
<P>0
</TD>
<TD WIDTH="9%" VALIGN="Top" ALIGN="Left">
<P>RES CHIP 
<P>4.7K 
<P>1/16W 
<P>+-1%(0402)
</TD>
<TD WIDTH="9%" VALIGN="Top" ALIGN="Left">
<P>EMPTY
</TD>
<TD WIDTH="3%" VALIGN="Top" ALIGN="Right">
<P>7
</TD>
<TD WIDTH="9%" VALIGN="Top" ALIGN="Left">
<P>?
</TD>
<TD WIDTH="9%" VALIGN="Top" ALIGN="Left">
<P>?
</TD>
<TD WIDTH="18%" VALIGN="Top" ALIGN="Left">
<P>R11,R164,R555,R556,
<P>R560,R686,R687
</TD>
<TD WIDTH="9%" VALIGN="Top" ALIGN="Left">
<P>?
</TD>
<TD WIDTH="9%" VALIGN="Top" ALIGN="Left">
<P>Comp-Appro
<P>ve
</TD>
<TD WIDTH="9%" VALIGN="Top" ALIGN="Left">
<P>End of 
<P>Design
</TD>
</TR>
<TR>
<TD WIDTH="5%" VALIGN="Top" ALIGN="Right">
<P>126
</TD>
<TD WIDTH="9%" VALIGN="Top" ALIGN="Left">
<P>CS24702FB1
<P>0
</TD>
<TD WIDTH="9%" VALIGN="Top" ALIGN="Left">
<P>RES CHIP 
<P>4.7K 
<P>1/16W 
<P>+-1%(0402)
</TD>
<TD WIDTH="9%" VALIGN="Top" ALIGN="Left">
<P>CHIP
</TD>
<TD WIDTH="3%" VALIGN="Top" ALIGN="Right">
<P>3
</TD>
<TD WIDTH="9%" VALIGN="Top" ALIGN="Left">
<P>?
</TD>
<TD WIDTH="9%" VALIGN="Top" ALIGN="Left">
<P>?
</TD>
<TD WIDTH="18%" VALIGN="Top" ALIGN="Left">
<P>R557,R558,R559
</TD>
<TD WIDTH="9%" VALIGN="Top" ALIGN="Left">
<P>?
</TD>
<TD WIDTH="9%" VALIGN="Top" ALIGN="Left">
<P>Comp-Appro
<P>ve
</TD>
<TD WIDTH="9%" VALIGN="Top" ALIGN="Left">
<P>End of 
<P>Design
</TD>
</TR>
<TR>
<TD WIDTH="5%" VALIGN="Top" ALIGN="Right">
<P>127
</TD>
<TD WIDTH="9%" VALIGN="Top" ALIGN="Left">
<P>CS25362FB0
<P>2
</TD>
<TD WIDTH="9%" VALIGN="Top" ALIGN="Left">
<P>RES CHIP 
<P>5.36K 
<P>1/16W 
<P>+-1%(0402)
<P>EF
</TD>
<TD WIDTH="9%" VALIGN="Top" ALIGN="Left">
<P>CHIP
</TD>
<TD WIDTH="3%" VALIGN="Top" ALIGN="Right">
<P>1
</TD>
<TD WIDTH="9%" VALIGN="Top" ALIGN="Left">
<P>?
</TD>
<TD WIDTH="9%" VALIGN="Top" ALIGN="Left">
<P>?
</TD>
<TD WIDTH="18%" VALIGN="Top" ALIGN="Left">
<P>R787
</TD>
<TD WIDTH="9%" VALIGN="Top" ALIGN="Left">
<P>?
</TD>
<TD WIDTH="9%" VALIGN="Top" ALIGN="Left">
<P>Comp-Appro
<P>ve
</TD>
<TD WIDTH="9%" VALIGN="Top" ALIGN="Left">
<P>End of 
<P>Design
</TD>
</TR>
<TR>
<TD WIDTH="5%" VALIGN="Top" ALIGN="Right">
<P>128
</TD>
<TD WIDTH="9%" VALIGN="Top" ALIGN="Left">
<P>CS25492FB0
<P>2
</TD>
<TD WIDTH="9%" VALIGN="Top" ALIGN="Left">
<P>RES CHIP 
<P>5.49K 
<P>1/16W 
<P>+-1%(0402)
<P> EF
</TD>
<TD WIDTH="9%" VALIGN="Top" ALIGN="Left">
<P>CHIP
</TD>
<TD WIDTH="3%" VALIGN="Top" ALIGN="Right">
<P>1
</TD>
<TD WIDTH="9%" VALIGN="Top" ALIGN="Left">
<P>?
</TD>
<TD WIDTH="9%" VALIGN="Top" ALIGN="Left">
<P>?
</TD>
<TD WIDTH="18%" VALIGN="Top" ALIGN="Left">
<P>PR276
</TD>
<TD WIDTH="9%" VALIGN="Top" ALIGN="Left">
<P>?
</TD>
<TD WIDTH="9%" VALIGN="Top" ALIGN="Left">
<P>Comp-Appro
<P>ve
</TD>
<TD WIDTH="9%" VALIGN="Top" ALIGN="Left">
<P>End of 
<P>Design
</TD>
</TR>
<TR>
<TD WIDTH="5%" VALIGN="Top" ALIGN="Right">
<P>129
</TD>
<TD WIDTH="9%" VALIGN="Top" ALIGN="Left">
<P>CS28202JB0
<P>5
</TD>
<TD WIDTH="9%" VALIGN="Top" ALIGN="Left">
<P>RES CHIP 
<P>8.2K 
<P>1/16W 
<P>+-5% 
<P>(0402) EF
</TD>
<TD WIDTH="9%" VALIGN="Top" ALIGN="Left">
<P>CHIP
</TD>
<TD WIDTH="3%" VALIGN="Top" ALIGN="Right">
<P>3
</TD>
<TD WIDTH="9%" VALIGN="Top" ALIGN="Left">
<P>?
</TD>
<TD WIDTH="9%" VALIGN="Top" ALIGN="Left">
<P>?
</TD>
<TD WIDTH="18%" VALIGN="Top" ALIGN="Left">
<P>R504,R768,R839
</TD>
<TD WIDTH="9%" VALIGN="Top" ALIGN="Left">
<P>?
</TD>
<TD WIDTH="9%" VALIGN="Top" ALIGN="Left">
<P>Comp-Appro
<P>ve
</TD>
<TD WIDTH="9%" VALIGN="Top" ALIGN="Left">
<P>End of 
<P>Design
</TD>
</TR>
<TR>
<TD WIDTH="5%" VALIGN="Top" ALIGN="Right">
<P>130
</TD>
<TD WIDTH="9%" VALIGN="Top" ALIGN="Left">
<P>CS28202JB0
<P>5
</TD>
<TD WIDTH="9%" VALIGN="Top" ALIGN="Left">
<P>RES CHIP 
<P>8.2K 
<P>1/16W 
<P>+-5% 
<P>(0402) EF
</TD>
<TD WIDTH="9%" VALIGN="Top" ALIGN="Left">
<P>EMPTY
</TD>
<TD WIDTH="3%" VALIGN="Top" ALIGN="Right">
<P>1
</TD>
<TD WIDTH="9%" VALIGN="Top" ALIGN="Left">
<P>?
</TD>
<TD WIDTH="9%" VALIGN="Top" ALIGN="Left">
<P>?
</TD>
<TD WIDTH="18%" VALIGN="Top" ALIGN="Left">
<P>R619
</TD>
<TD WIDTH="9%" VALIGN="Top" ALIGN="Left">
<P>?
</TD>
<TD WIDTH="9%" VALIGN="Top" ALIGN="Left">
<P>Comp-Appro
<P>ve
</TD>
<TD WIDTH="9%" VALIGN="Top" ALIGN="Left">
<P>End of 
<P>Design
</TD>
</TR>
<TR>
<TD WIDTH="5%" VALIGN="Top" ALIGN="Right">
<P>131
</TD>
<TD WIDTH="9%" VALIGN="Top" ALIGN="Left">
<P>CS31002FB0
<P>8
</TD>
<TD WIDTH="9%" VALIGN="Top" ALIGN="Left">
<P>RES CHIP 
<P>10K 1/16W 
<P>+-1%(0402)
<P>EF
</TD>
<TD WIDTH="9%" VALIGN="Top" ALIGN="Left">
<P>CHIP
</TD>
<TD WIDTH="3%" VALIGN="Top" ALIGN="Right">
<P>36
</TD>
<TD WIDTH="9%" VALIGN="Top" ALIGN="Left">
<P>?
</TD>
<TD WIDTH="9%" VALIGN="Top" ALIGN="Left">
<P>?
</TD>
<TD WIDTH="18%" VALIGN="Top" ALIGN="Left">
<P>PR241,PR242,PR244,
<P>PR255,PR498,PR500,
<P>R10,R50,R54,R59,
<P>R126,R136,R203,R204,
<P>R209,R211,R226,R227,
<P>R230,R288,R289,R295,
<P>R306,R383,R464,R497,
<P>R508,R523,R709,R716,
<P>R808,R809,R810,R814,
<P>R815,R866
</TD>
<TD WIDTH="9%" VALIGN="Top" ALIGN="Left">
<P>?
</TD>
<TD WIDTH="9%" VALIGN="Top" ALIGN="Left">
<P>Comp-Appro
<P>ve
</TD>
<TD WIDTH="9%" VALIGN="Top" ALIGN="Left">
<P>End of 
<P>Design
</TD>
</TR>
<TR>
<TD WIDTH="5%" VALIGN="Top" ALIGN="Right">
<P>132
</TD>
<TD WIDTH="9%" VALIGN="Top" ALIGN="Left">
<P>CS31002FB0
<P>8
</TD>
<TD WIDTH="9%" VALIGN="Top" ALIGN="Left">
<P>RES CHIP 
<P>10K 1/16W 
<P>+-1%(0402)
<P>EF
</TD>
<TD WIDTH="9%" VALIGN="Top" ALIGN="Left">
<P>EMPTY
</TD>
<TD WIDTH="3%" VALIGN="Top" ALIGN="Right">
<P>6
</TD>
<TD WIDTH="9%" VALIGN="Top" ALIGN="Left">
<P>?
</TD>
<TD WIDTH="9%" VALIGN="Top" ALIGN="Left">
<P>?
</TD>
<TD WIDTH="18%" VALIGN="Top" ALIGN="Left">
<P>R41,R202,R228,R377,
<P>R712,R834
</TD>
<TD WIDTH="9%" VALIGN="Top" ALIGN="Left">
<P>?
</TD>
<TD WIDTH="9%" VALIGN="Top" ALIGN="Left">
<P>Comp-Appro
<P>ve
</TD>
<TD WIDTH="9%" VALIGN="Top" ALIGN="Left">
<P>End of 
<P>Design
</TD>
</TR>
<TR>
<TD WIDTH="5%" VALIGN="Top" ALIGN="Right">
<P>133
</TD>
<TD WIDTH="9%" VALIGN="Top" ALIGN="Left">
<P>CS31002FB2
<P>6
</TD>
<TD WIDTH="9%" VALIGN="Top" ALIGN="Left">
<P>RES CHIP 
<P>10K 1/16W 
<P>+-1% 
<P>(0402)
</TD>
<TD WIDTH="9%" VALIGN="Top" ALIGN="Left">
<P>EMPTY
</TD>
<TD WIDTH="3%" VALIGN="Top" ALIGN="Right">
<P>10
</TD>
<TD WIDTH="9%" VALIGN="Top" ALIGN="Left">
<P>?
</TD>
<TD WIDTH="9%" VALIGN="Top" ALIGN="Left">
<P>?
</TD>
<TD WIDTH="18%" VALIGN="Top" ALIGN="Left">
<P>R297,R655,R656,R657,
<P>R658,R659,R660,R661,
<P>R662,R663
</TD>
<TD WIDTH="9%" VALIGN="Top" ALIGN="Left">
<P>?
</TD>
<TD WIDTH="9%" VALIGN="Top" ALIGN="Left">
<P>Comp-Appro
<P>ve
</TD>
<TD WIDTH="9%" VALIGN="Top" ALIGN="Left">
<P>End of 
<P>Design
</TD>
</TR>
<TR>
<TD WIDTH="5%" VALIGN="Top" ALIGN="Right">
<P>134
</TD>
<TD WIDTH="9%" VALIGN="Top" ALIGN="Left">
<P>CS31202FB0
<P>4
</TD>
<TD WIDTH="9%" VALIGN="Top" ALIGN="Left">
<P>RES CHIP 
<P>12K 1/16W 
<P>+-1%(0402)
<P>EF
</TD>
<TD WIDTH="9%" VALIGN="Top" ALIGN="Left">
<P>CHIP
</TD>
<TD WIDTH="3%" VALIGN="Top" ALIGN="Right">
<P>2
</TD>
<TD WIDTH="9%" VALIGN="Top" ALIGN="Left">
<P>?
</TD>
<TD WIDTH="9%" VALIGN="Top" ALIGN="Left">
<P>?
</TD>
<TD WIDTH="18%" VALIGN="Top" ALIGN="Left">
<P>R830,R832
</TD>
<TD WIDTH="9%" VALIGN="Top" ALIGN="Left">
<P>?
</TD>
<TD WIDTH="9%" VALIGN="Top" ALIGN="Left">
<P>Comp-Appro
<P>ve
</TD>
<TD WIDTH="9%" VALIGN="Top" ALIGN="Left">
<P>End of 
<P>Design
</TD>
</TR>
<TR>
<TD WIDTH="5%" VALIGN="Top" ALIGN="Right">
<P>135
</TD>
<TD WIDTH="9%" VALIGN="Top" ALIGN="Left">
<P>CS31242FB0
<P>2
</TD>
<TD WIDTH="9%" VALIGN="Top" ALIGN="Left">
<P>RES CHIP 
<P>12.4K 
<P>1/16W 
<P>+-1%(0402)
<P>EF
</TD>
<TD WIDTH="9%" VALIGN="Top" ALIGN="Left">
<P>CHIP
</TD>
<TD WIDTH="3%" VALIGN="Top" ALIGN="Right">
<P>2
</TD>
<TD WIDTH="9%" VALIGN="Top" ALIGN="Left">
<P>?
</TD>
<TD WIDTH="9%" VALIGN="Top" ALIGN="Left">
<P>?
</TD>
<TD WIDTH="18%" VALIGN="Top" ALIGN="Left">
<P>PR526,PR530
</TD>
<TD WIDTH="9%" VALIGN="Top" ALIGN="Left">
<P>?
</TD>
<TD WIDTH="9%" VALIGN="Top" ALIGN="Left">
<P>Comp-Appro
<P>ve
</TD>
<TD WIDTH="9%" VALIGN="Top" ALIGN="Left">
<P>End of 
<P>Design
</TD>
</TR>
<TR>
<TD WIDTH="5%" VALIGN="Top" ALIGN="Right">
<P>136
</TD>
<TD WIDTH="9%" VALIGN="Top" ALIGN="Left">
<P>CS31502FB0
<P>5
</TD>
<TD WIDTH="9%" VALIGN="Top" ALIGN="Left">
<P>RES CHIP 
<P>15K 1/16W 
<P>+-1%(0402)
<P>EF
</TD>
<TD WIDTH="9%" VALIGN="Top" ALIGN="Left">
<P>CHIP
</TD>
<TD WIDTH="3%" VALIGN="Top" ALIGN="Right">
<P>1
</TD>
<TD WIDTH="9%" VALIGN="Top" ALIGN="Left">
<P>?
</TD>
<TD WIDTH="9%" VALIGN="Top" ALIGN="Left">
<P>?
</TD>
<TD WIDTH="18%" VALIGN="Top" ALIGN="Left">
<P>R831
</TD>
<TD WIDTH="9%" VALIGN="Top" ALIGN="Left">
<P>?
</TD>
<TD WIDTH="9%" VALIGN="Top" ALIGN="Left">
<P>Comp-Appro
<P>ve
</TD>
<TD WIDTH="9%" VALIGN="Top" ALIGN="Left">
<P>End of 
<P>Design
</TD>
</TR>
<TR>
<TD WIDTH="5%" VALIGN="Top" ALIGN="Right">
<P>137
</TD>
<TD WIDTH="9%" VALIGN="Top" ALIGN="Left">
<P>CS31582FB0
<P>2
</TD>
<TD WIDTH="9%" VALIGN="Top" ALIGN="Left">
<P>RES CHIP 
<P>15.8K 
<P>1/16W 
<P>+-1% 
<P>(0402)EF
</TD>
<TD WIDTH="9%" VALIGN="Top" ALIGN="Left">
<P>CHIP
</TD>
<TD WIDTH="3%" VALIGN="Top" ALIGN="Right">
<P>1
</TD>
<TD WIDTH="9%" VALIGN="Top" ALIGN="Left">
<P>?
</TD>
<TD WIDTH="9%" VALIGN="Top" ALIGN="Left">
<P>?
</TD>
<TD WIDTH="18%" VALIGN="Top" ALIGN="Left">
<P>R785
</TD>
<TD WIDTH="9%" VALIGN="Top" ALIGN="Left">
<P>?
</TD>
<TD WIDTH="9%" VALIGN="Top" ALIGN="Left">
<P>Comp-Appro
<P>ve
</TD>
<TD WIDTH="9%" VALIGN="Top" ALIGN="Left">
<P>End of 
<P>Design
</TD>
</TR>
<TR>
<TD WIDTH="5%" VALIGN="Top" ALIGN="Right">
<P>138
</TD>
<TD WIDTH="9%" VALIGN="Top" ALIGN="Left">
<P>CS32002FB0
<P>6
</TD>
<TD WIDTH="9%" VALIGN="Top" ALIGN="Left">
<P>RES CHIP 
<P>20K 1/16W 
<P>+-1%(0402)
<P>EF
</TD>
<TD WIDTH="9%" VALIGN="Top" ALIGN="Left">
<P>CHIP
</TD>
<TD WIDTH="3%" VALIGN="Top" ALIGN="Right">
<P>2
</TD>
<TD WIDTH="9%" VALIGN="Top" ALIGN="Left">
<P>?
</TD>
<TD WIDTH="9%" VALIGN="Top" ALIGN="Left">
<P>?
</TD>
<TD WIDTH="18%" VALIGN="Top" ALIGN="Left">
<P>R205,R378
</TD>
<TD WIDTH="9%" VALIGN="Top" ALIGN="Left">
<P>?
</TD>
<TD WIDTH="9%" VALIGN="Top" ALIGN="Left">
<P>Comp-Appro
<P>ve
</TD>
<TD WIDTH="9%" VALIGN="Top" ALIGN="Left">
<P>End of 
<P>Design
</TD>
</TR>
<TR>
<TD WIDTH="5%" VALIGN="Top" ALIGN="Right">
<P>139
</TD>
<TD WIDTH="9%" VALIGN="Top" ALIGN="Left">
<P>CS32052FB0
<P>2
</TD>
<TD WIDTH="9%" VALIGN="Top" ALIGN="Left">
<P>RES CHIP 
<P>20.5K 
<P>1/16W 
<P>+-1%(0402)
<P>EF
</TD>
<TD WIDTH="9%" VALIGN="Top" ALIGN="Left">
<P>CHIP
</TD>
<TD WIDTH="3%" VALIGN="Top" ALIGN="Right">
<P>1
</TD>
<TD WIDTH="9%" VALIGN="Top" ALIGN="Left">
<P>?
</TD>
<TD WIDTH="9%" VALIGN="Top" ALIGN="Left">
<P>?
</TD>
<TD WIDTH="18%" VALIGN="Top" ALIGN="Left">
<P>PR525
</TD>
<TD WIDTH="9%" VALIGN="Top" ALIGN="Left">
<P>?
</TD>
<TD WIDTH="9%" VALIGN="Top" ALIGN="Left">
<P>Comp-Relea
<P>se Qty
</TD>
<TD WIDTH="9%" VALIGN="Top" ALIGN="Left">
<P>End of 
<P>Design
</TD>
</TR>
<TR>
<TD WIDTH="5%" VALIGN="Top" ALIGN="Right">
<P>140
</TD>
<TD WIDTH="9%" VALIGN="Top" ALIGN="Left">
<P>CS32552FB0
<P>6
</TD>
<TD WIDTH="9%" VALIGN="Top" ALIGN="Left">
<P>RES CHIP 
<P>25.5K 
<P>1/16W 
<P>+-1%(0402)
<P>EF
</TD>
<TD WIDTH="9%" VALIGN="Top" ALIGN="Left">
<P>CHIP
</TD>
<TD WIDTH="3%" VALIGN="Top" ALIGN="Right">
<P>1
</TD>
<TD WIDTH="9%" VALIGN="Top" ALIGN="Left">
<P>?
</TD>
<TD WIDTH="9%" VALIGN="Top" ALIGN="Left">
<P>?
</TD>
<TD WIDTH="18%" VALIGN="Top" ALIGN="Left">
<P>R829
</TD>
<TD WIDTH="9%" VALIGN="Top" ALIGN="Left">
<P>?
</TD>
<TD WIDTH="9%" VALIGN="Top" ALIGN="Left">
<P>Comp-Appro
<P>ve
</TD>
<TD WIDTH="9%" VALIGN="Top" ALIGN="Left">
<P>End of 
<P>Design
</TD>
</TR>
<TR>
<TD WIDTH="5%" VALIGN="Top" ALIGN="Right">
<P>141
</TD>
<TD WIDTH="9%" VALIGN="Top" ALIGN="Left">
<P>CS34702FB0
<P>1
</TD>
<TD WIDTH="9%" VALIGN="Top" ALIGN="Left">
<P>RES CHIP 
<P>47K 1/16W 
<P>+-1%(0402)
<P>EF
</TD>
<TD WIDTH="9%" VALIGN="Top" ALIGN="Left">
<P>CHIP
</TD>
<TD WIDTH="3%" VALIGN="Top" ALIGN="Right">
<P>2
</TD>
<TD WIDTH="9%" VALIGN="Top" ALIGN="Left">
<P>?
</TD>
<TD WIDTH="9%" VALIGN="Top" ALIGN="Left">
<P>?
</TD>
<TD WIDTH="18%" VALIGN="Top" ALIGN="Left">
<P>R290,R776
</TD>
<TD WIDTH="9%" VALIGN="Top" ALIGN="Left">
<P>?
</TD>
<TD WIDTH="9%" VALIGN="Top" ALIGN="Left">
<P>Comp-Appro
<P>ve
</TD>
<TD WIDTH="9%" VALIGN="Top" ALIGN="Left">
<P>End of 
<P>Design
</TD>
</TR>
<TR>
<TD WIDTH="5%" VALIGN="Top" ALIGN="Right">
<P>142
</TD>
<TD WIDTH="9%" VALIGN="Top" ALIGN="Left">
<P>CS34702FB0
<P>1
</TD>
<TD WIDTH="9%" VALIGN="Top" ALIGN="Left">
<P>RES CHIP 
<P>47K 1/16W 
<P>+-1%(0402)
<P>EF
</TD>
<TD WIDTH="9%" VALIGN="Top" ALIGN="Left">
<P>EMPTY
</TD>
<TD WIDTH="3%" VALIGN="Top" ALIGN="Right">
<P>1
</TD>
<TD WIDTH="9%" VALIGN="Top" ALIGN="Left">
<P>?
</TD>
<TD WIDTH="9%" VALIGN="Top" ALIGN="Left">
<P>?
</TD>
<TD WIDTH="18%" VALIGN="Top" ALIGN="Left">
<P>R312
</TD>
<TD WIDTH="9%" VALIGN="Top" ALIGN="Left">
<P>?
</TD>
<TD WIDTH="9%" VALIGN="Top" ALIGN="Left">
<P>Comp-Appro
<P>ve
</TD>
<TD WIDTH="9%" VALIGN="Top" ALIGN="Left">
<P>End of 
<P>Design
</TD>
</TR>
<TR>
<TD WIDTH="5%" VALIGN="Top" ALIGN="Right">
<P>143
</TD>
<TD WIDTH="9%" VALIGN="Top" ALIGN="Left">
<P>CS34992FB0
<P>5
</TD>
<TD WIDTH="9%" VALIGN="Top" ALIGN="Left">
<P>RES CHIP 
<P>49.9K 
<P>1/16W 
<P>+-1%(0402)
<P>EF
</TD>
<TD WIDTH="9%" VALIGN="Top" ALIGN="Left">
<P>CHIP
</TD>
<TD WIDTH="3%" VALIGN="Top" ALIGN="Right">
<P>2
</TD>
<TD WIDTH="9%" VALIGN="Top" ALIGN="Left">
<P>?
</TD>
<TD WIDTH="9%" VALIGN="Top" ALIGN="Left">
<P>?
</TD>
<TD WIDTH="18%" VALIGN="Top" ALIGN="Left">
<P>R233,R234
</TD>
<TD WIDTH="9%" VALIGN="Top" ALIGN="Left">
<P>?
</TD>
<TD WIDTH="9%" VALIGN="Top" ALIGN="Left">
<P>Comp-Appro
<P>ve
</TD>
<TD WIDTH="9%" VALIGN="Top" ALIGN="Left">
<P>End of 
<P>Design
</TD>
</TR>
<TR>
<TD WIDTH="5%" VALIGN="Top" ALIGN="Right">
<P>144
</TD>
<TD WIDTH="9%" VALIGN="Top" ALIGN="Left">
<P>CS35602FB0
<P>0
</TD>
<TD WIDTH="9%" VALIGN="Top" ALIGN="Left">
<P>RES CHIP 
<P>56K 1/16W 
<P>+-1%(0402)
<P>EF
</TD>
<TD WIDTH="9%" VALIGN="Top" ALIGN="Left">
<P>CHIP
</TD>
<TD WIDTH="3%" VALIGN="Top" ALIGN="Right">
<P>1
</TD>
<TD WIDTH="9%" VALIGN="Top" ALIGN="Left">
<P>?
</TD>
<TD WIDTH="9%" VALIGN="Top" ALIGN="Left">
<P>?
</TD>
<TD WIDTH="18%" VALIGN="Top" ALIGN="Left">
<P>PR534
</TD>
<TD WIDTH="9%" VALIGN="Top" ALIGN="Left">
<P>?
</TD>
<TD WIDTH="9%" VALIGN="Top" ALIGN="Left">
<P>?
</TD>
<TD WIDTH="9%" VALIGN="Top" ALIGN="Left">
<P>?
</TD>
</TR>
<TR>
<TD WIDTH="5%" VALIGN="Top" ALIGN="Right">
<P>145
</TD>
<TD WIDTH="9%" VALIGN="Top" ALIGN="Left">
<P>CS36042FB0
<P>4
</TD>
<TD WIDTH="9%" VALIGN="Top" ALIGN="Left">
<P>RES CHIP 
<P>60.4K 
<P>1/16W 
<P>+-1%(0402)
<P>EF
</TD>
<TD WIDTH="9%" VALIGN="Top" ALIGN="Left">
<P>CHIP
</TD>
<TD WIDTH="3%" VALIGN="Top" ALIGN="Right">
<P>1
</TD>
<TD WIDTH="9%" VALIGN="Top" ALIGN="Left">
<P>?
</TD>
<TD WIDTH="9%" VALIGN="Top" ALIGN="Left">
<P>?
</TD>
<TD WIDTH="18%" VALIGN="Top" ALIGN="Left">
<P>PR532
</TD>
<TD WIDTH="9%" VALIGN="Top" ALIGN="Left">
<P>?
</TD>
<TD WIDTH="9%" VALIGN="Top" ALIGN="Left">
<P>Comp-Appro
<P>ve
</TD>
<TD WIDTH="9%" VALIGN="Top" ALIGN="Left">
<P>End of 
<P>Design
</TD>
</TR>
<TR>
<TD WIDTH="5%" VALIGN="Top" ALIGN="Right">
<P>146
</TD>
<TD WIDTH="9%" VALIGN="Top" ALIGN="Left">
<P>CS39102FB0
<P>6
</TD>
<TD WIDTH="9%" VALIGN="Top" ALIGN="Left">
<P>RES CHIP 
<P>91K 1/16W 
<P>+-1%(0402)
<P>EF
</TD>
<TD WIDTH="9%" VALIGN="Top" ALIGN="Left">
<P>CHIP
</TD>
<TD WIDTH="3%" VALIGN="Top" ALIGN="Right">
<P>1
</TD>
<TD WIDTH="9%" VALIGN="Top" ALIGN="Left">
<P>?
</TD>
<TD WIDTH="9%" VALIGN="Top" ALIGN="Left">
<P>?
</TD>
<TD WIDTH="18%" VALIGN="Top" ALIGN="Left">
<P>PR527
</TD>
<TD WIDTH="9%" VALIGN="Top" ALIGN="Left">
<P>?
</TD>
<TD WIDTH="9%" VALIGN="Top" ALIGN="Left">
<P>?
</TD>
<TD WIDTH="9%" VALIGN="Top" ALIGN="Left">
<P>?
</TD>
</TR>
<TR>
<TD WIDTH="5%" VALIGN="Top" ALIGN="Right">
<P>147
</TD>
<TD WIDTH="9%" VALIGN="Top" ALIGN="Left">
<P>CS41002BB0
<P>8
</TD>
<TD WIDTH="9%" VALIGN="Top" ALIGN="Left">
<P>RES CHIP 
<P>100K 
<P>1/16W 
<P>+-0.1%(040
<P>2)EF
</TD>
<TD WIDTH="9%" VALIGN="Top" ALIGN="Left">
<P>CHIP
</TD>
<TD WIDTH="3%" VALIGN="Top" ALIGN="Right">
<P>1
</TD>
<TD WIDTH="9%" VALIGN="Top" ALIGN="Left">
<P>?
</TD>
<TD WIDTH="9%" VALIGN="Top" ALIGN="Left">
<P>?
</TD>
<TD WIDTH="18%" VALIGN="Top" ALIGN="Left">
<P>PR543
</TD>
<TD WIDTH="9%" VALIGN="Top" ALIGN="Left">
<P>?
</TD>
<TD WIDTH="9%" VALIGN="Top" ALIGN="Left">
<P>?
</TD>
<TD WIDTH="9%" VALIGN="Top" ALIGN="Left">
<P>?
</TD>
</TR>
<TR>
<TD WIDTH="5%" VALIGN="Top" ALIGN="Right">
<P>148
</TD>
<TD WIDTH="9%" VALIGN="Top" ALIGN="Left">
<P>CS41002FB0
<P>9
</TD>
<TD WIDTH="9%" VALIGN="Top" ALIGN="Left">
<P>RES CHIP 
<P>100K 
<P>1/16W 
<P>+-1%(0402)
<P>EF
</TD>
<TD WIDTH="9%" VALIGN="Top" ALIGN="Left">
<P>EMPTY
</TD>
<TD WIDTH="3%" VALIGN="Top" ALIGN="Right">
<P>9
</TD>
<TD WIDTH="9%" VALIGN="Top" ALIGN="Left">
<P>?
</TD>
<TD WIDTH="9%" VALIGN="Top" ALIGN="Left">
<P>?
</TD>
<TD WIDTH="18%" VALIGN="Top" ALIGN="Left">
<P>PR245,R206,R219,
<P>R274,R296,R817,R818,
<P>R819,R820
</TD>
<TD WIDTH="9%" VALIGN="Top" ALIGN="Left">
<P>?
</TD>
<TD WIDTH="9%" VALIGN="Top" ALIGN="Left">
<P>Comp-Appro
<P>ve
</TD>
<TD WIDTH="9%" VALIGN="Top" ALIGN="Left">
<P>End of 
<P>Design
</TD>
</TR>
<TR>
<TD WIDTH="5%" VALIGN="Top" ALIGN="Right">
<P>149
</TD>
<TD WIDTH="9%" VALIGN="Top" ALIGN="Left">
<P>CS41002FB0
<P>9
</TD>
<TD WIDTH="9%" VALIGN="Top" ALIGN="Left">
<P>RES CHIP 
<P>100K 
<P>1/16W 
<P>+-1%(0402)
<P>EF
</TD>
<TD WIDTH="9%" VALIGN="Top" ALIGN="Left">
<P>CHIP
</TD>
<TD WIDTH="3%" VALIGN="Top" ALIGN="Right">
<P>17
</TD>
<TD WIDTH="9%" VALIGN="Top" ALIGN="Left">
<P>?
</TD>
<TD WIDTH="9%" VALIGN="Top" ALIGN="Left">
<P>?
</TD>
<TD WIDTH="18%" VALIGN="Top" ALIGN="Left">
<P>PR522,R66,R118,R193,
<P>R273,R314,R391,R392,
<P>R478,R502,R614,R620,
<P>R642,R710,R755,R778,
<P>R823
</TD>
<TD WIDTH="9%" VALIGN="Top" ALIGN="Left">
<P>?
</TD>
<TD WIDTH="9%" VALIGN="Top" ALIGN="Left">
<P>Comp-Appro
<P>ve
</TD>
<TD WIDTH="9%" VALIGN="Top" ALIGN="Left">
<P>End of 
<P>Design
</TD>
</TR>
<TR>
<TD WIDTH="5%" VALIGN="Top" ALIGN="Right">
<P>150
</TD>
<TD WIDTH="9%" VALIGN="Top" ALIGN="Left">
<P>CS41502FB0
<P>4
</TD>
<TD WIDTH="9%" VALIGN="Top" ALIGN="Left">
<P>RES CHIP 
<P>150K 
<P>1/16W 
<P>+-1%(0402)
<P>EF
</TD>
<TD WIDTH="9%" VALIGN="Top" ALIGN="Left">
<P>CHIP
</TD>
<TD WIDTH="3%" VALIGN="Top" ALIGN="Right">
<P>1
</TD>
<TD WIDTH="9%" VALIGN="Top" ALIGN="Left">
<P>?
</TD>
<TD WIDTH="9%" VALIGN="Top" ALIGN="Left">
<P>?
</TD>
<TD WIDTH="18%" VALIGN="Top" ALIGN="Left">
<P>PR496
</TD>
<TD WIDTH="9%" VALIGN="Top" ALIGN="Left">
<P>?
</TD>
<TD WIDTH="9%" VALIGN="Top" ALIGN="Left">
<P>Comp-Appro
<P>ve
</TD>
<TD WIDTH="9%" VALIGN="Top" ALIGN="Left">
<P>End of 
<P>Design
</TD>
</TR>
<TR>
<TD WIDTH="5%" VALIGN="Top" ALIGN="Right">
<P>151
</TD>
<TD WIDTH="9%" VALIGN="Top" ALIGN="Left">
<P>CS41502FB0
<P>4
</TD>
<TD WIDTH="9%" VALIGN="Top" ALIGN="Left">
<P>RES CHIP 
<P>150K 
<P>1/16W 
<P>+-1%(0402)
<P>EF
</TD>
<TD WIDTH="9%" VALIGN="Top" ALIGN="Left">
<P>EMPTY
</TD>
<TD WIDTH="3%" VALIGN="Top" ALIGN="Right">
<P>1
</TD>
<TD WIDTH="9%" VALIGN="Top" ALIGN="Left">
<P>?
</TD>
<TD WIDTH="9%" VALIGN="Top" ALIGN="Left">
<P>?
</TD>
<TD WIDTH="18%" VALIGN="Top" ALIGN="Left">
<P>R493
</TD>
<TD WIDTH="9%" VALIGN="Top" ALIGN="Left">
<P>?
</TD>
<TD WIDTH="9%" VALIGN="Top" ALIGN="Left">
<P>Comp-Appro
<P>ve
</TD>
<TD WIDTH="9%" VALIGN="Top" ALIGN="Left">
<P>End of 
<P>Design
</TD>
</TR>
<TR>
<TD WIDTH="5%" VALIGN="Top" ALIGN="Right">
<P>152
</TD>
<TD WIDTH="9%" VALIGN="Top" ALIGN="Left">
<P>CS42002FB0
<P>5
</TD>
<TD WIDTH="9%" VALIGN="Top" ALIGN="Left">
<P>RES CHIP 
<P>200K 
<P>1/16W 
<P>+-1%(0402)
<P>EF
</TD>
<TD WIDTH="9%" VALIGN="Top" ALIGN="Left">
<P>CHIP
</TD>
<TD WIDTH="3%" VALIGN="Top" ALIGN="Right">
<P>1
</TD>
<TD WIDTH="9%" VALIGN="Top" ALIGN="Left">
<P>?
</TD>
<TD WIDTH="9%" VALIGN="Top" ALIGN="Left">
<P>?
</TD>
<TD WIDTH="18%" VALIGN="Top" ALIGN="Left">
<P>R777
</TD>
<TD WIDTH="9%" VALIGN="Top" ALIGN="Left">
<P>?
</TD>
<TD WIDTH="9%" VALIGN="Top" ALIGN="Left">
<P>Comp-Appro
<P>ve
</TD>
<TD WIDTH="9%" VALIGN="Top" ALIGN="Left">
<P>End of 
<P>Design
</TD>
</TR>
<TR>
<TD WIDTH="5%" VALIGN="Top" ALIGN="Right">
<P>153
</TD>
<TD WIDTH="9%" VALIGN="Top" ALIGN="Left">
<P>CS44702FB0
<P>2
</TD>
<TD WIDTH="9%" VALIGN="Top" ALIGN="Left">
<P>RES CHIP 
<P>470K 
<P>1/16W 
<P>+-1%(0402)
<P>EF
</TD>
<TD WIDTH="9%" VALIGN="Top" ALIGN="Left">
<P>CHIP
</TD>
<TD WIDTH="3%" VALIGN="Top" ALIGN="Right">
<P>1
</TD>
<TD WIDTH="9%" VALIGN="Top" ALIGN="Left">
<P>?
</TD>
<TD WIDTH="9%" VALIGN="Top" ALIGN="Left">
<P>?
</TD>
<TD WIDTH="18%" VALIGN="Top" ALIGN="Left">
<P>R313
</TD>
<TD WIDTH="9%" VALIGN="Top" ALIGN="Left">
<P>?
</TD>
<TD WIDTH="9%" VALIGN="Top" ALIGN="Left">
<P>Comp-Appro
<P>ve
</TD>
<TD WIDTH="9%" VALIGN="Top" ALIGN="Left">
<P>End of 
<P>Design
</TD>
</TR>
<TR>
<TD WIDTH="5%" VALIGN="Top" ALIGN="Right">
<P>154
</TD>
<TD WIDTH="9%" VALIGN="Top" ALIGN="Left">
<P>CS46812FB0
<P>6
</TD>
<TD WIDTH="9%" VALIGN="Top" ALIGN="Left">
<P>RES CHIP 
<P>681K 
<P>1/16W 
<P>+-1%(0402)
<P>EF
</TD>
<TD WIDTH="9%" VALIGN="Top" ALIGN="Left">
<P>CHIP
</TD>
<TD WIDTH="3%" VALIGN="Top" ALIGN="Right">
<P>1
</TD>
<TD WIDTH="9%" VALIGN="Top" ALIGN="Left">
<P>?
</TD>
<TD WIDTH="9%" VALIGN="Top" ALIGN="Left">
<P>?
</TD>
<TD WIDTH="18%" VALIGN="Top" ALIGN="Left">
<P>PR521
</TD>
<TD WIDTH="9%" VALIGN="Top" ALIGN="Left">
<P>?
</TD>
<TD WIDTH="9%" VALIGN="Top" ALIGN="Left">
<P>?
</TD>
<TD WIDTH="9%" VALIGN="Top" ALIGN="Left">
<P>?
</TD>
</TR>
<TR>
<TD WIDTH="5%" VALIGN="Top" ALIGN="Right">
<P>155
</TD>
<TD WIDTH="9%" VALIGN="Top" ALIGN="Left">
<P>CS51002FB0
<P>5
</TD>
<TD WIDTH="9%" VALIGN="Top" ALIGN="Left">
<P>RES CHIP 
<P>1M 1/16W 
<P>+-1%(0402)
<P>EF
</TD>
<TD WIDTH="9%" VALIGN="Top" ALIGN="Left">
<P>CHIP
</TD>
<TD WIDTH="3%" VALIGN="Top" ALIGN="Right">
<P>2
</TD>
<TD WIDTH="9%" VALIGN="Top" ALIGN="Left">
<P>?
</TD>
<TD WIDTH="9%" VALIGN="Top" ALIGN="Left">
<P>?
</TD>
<TD WIDTH="18%" VALIGN="Top" ALIGN="Left">
<P>R395,R396
</TD>
<TD WIDTH="9%" VALIGN="Top" ALIGN="Left">
<P>?
</TD>
<TD WIDTH="9%" VALIGN="Top" ALIGN="Left">
<P>Comp-Appro
<P>ve
</TD>
<TD WIDTH="9%" VALIGN="Top" ALIGN="Left">
<P>End of 
<P>Design
</TD>
</TR>
<TR>
<TD WIDTH="5%" VALIGN="Top" ALIGN="Right">
<P>156
</TD>
<TD WIDTH="9%" VALIGN="Top" ALIGN="Left">
<P>CV-10B0MZ1
<P>3
</TD>
<TD WIDTH="9%" VALIGN="Top" ALIGN="Left">
<P>IND SMD 
<P>1UH 
<P>20%11A(PCM
<P>C063T-1R0M
<P>N)
</TD>
<TD WIDTH="9%" VALIGN="Top" ALIGN="Left">
<P>IND
</TD>
<TD WIDTH="3%" VALIGN="Top" ALIGN="Right">
<P>2
</TD>
<TD WIDTH="9%" VALIGN="Top" ALIGN="Left">
<P>?
</TD>
<TD WIDTH="9%" VALIGN="Top" ALIGN="Left">
<P>?
</TD>
<TD WIDTH="18%" VALIGN="Top" ALIGN="Left">
<P>PL31,PL33
</TD>
<TD WIDTH="9%" VALIGN="Top" ALIGN="Left">
<P>?
</TD>
<TD WIDTH="9%" VALIGN="Top" ALIGN="Left">
<P>?
</TD>
<TD WIDTH="9%" VALIGN="Top" ALIGN="Left">
<P>?
</TD>
</TR>
<TR>
<TD WIDTH="5%" VALIGN="Top" ALIGN="Right">
<P>157
</TD>
<TD WIDTH="9%" VALIGN="Top" ALIGN="Left">
<P>CV-3360MZ0
<P>7
</TD>
<TD WIDTH="9%" VALIGN="Top" ALIGN="Left">
<P>IND SMD 
<P>3.3UH,
<P>6A20%(PCMC
<P>063T-3R3MN
<P>)
</TD>
<TD WIDTH="9%" VALIGN="Top" ALIGN="Left">
<P>IND
</TD>
<TD WIDTH="3%" VALIGN="Top" ALIGN="Right">
<P>1
</TD>
<TD WIDTH="9%" VALIGN="Top" ALIGN="Left">
<P>?
</TD>
<TD WIDTH="9%" VALIGN="Top" ALIGN="Left">
<P>?
</TD>
<TD WIDTH="18%" VALIGN="Top" ALIGN="Left">
<P>PL35
</TD>
<TD WIDTH="9%" VALIGN="Top" ALIGN="Left">
<P>?
</TD>
<TD WIDTH="9%" VALIGN="Top" ALIGN="Left">
<P>?
</TD>
<TD WIDTH="9%" VALIGN="Top" ALIGN="Left">
<P>?
</TD>
</TR>
<TR>
<TD WIDTH="5%" VALIGN="Top" ALIGN="Right">
<P>158
</TD>
<TD WIDTH="9%" VALIGN="Top" ALIGN="Left">
<P>CV-47A0MZ1
<P>0
</TD>
<TD WIDTH="9%" VALIGN="Top" ALIGN="Left">
<P>IND SMD 
<P>4.7UH 
<P>+-20% 
<P>10A(PCMB10
<P>4E-4R7MS)
</TD>
<TD WIDTH="9%" VALIGN="Top" ALIGN="Left">
<P>IND
</TD>
<TD WIDTH="3%" VALIGN="Top" ALIGN="Right">
<P>1
</TD>
<TD WIDTH="9%" VALIGN="Top" ALIGN="Left">
<P>?
</TD>
<TD WIDTH="9%" VALIGN="Top" ALIGN="Left">
<P>?
</TD>
<TD WIDTH="18%" VALIGN="Top" ALIGN="Left">
<P>PL34
</TD>
<TD WIDTH="9%" VALIGN="Top" ALIGN="Left">
<P>?
</TD>
<TD WIDTH="9%" VALIGN="Top" ALIGN="Left">
<P>?
</TD>
<TD WIDTH="9%" VALIGN="Top" ALIGN="Left">
<P>?
</TD>
</TR>
<TR>
<TD WIDTH="5%" VALIGN="Top" ALIGN="Right">
<P>159
</TD>
<TD WIDTH="9%" VALIGN="Top" ALIGN="Left">
<P>CX21SN6700
<P>0
</TD>
<TD WIDTH="9%" VALIGN="Top" ALIGN="Left">
<P>EMI 
<P>FILTER 
<P>DLW21SN670
<P>HQ2L(67,
<P>320MA)
</TD>
<TD WIDTH="9%" VALIGN="Top" ALIGN="Left">
<P>EMPTY
</TD>
<TD WIDTH="3%" VALIGN="Top" ALIGN="Right">
<P>3
</TD>
<TD WIDTH="9%" VALIGN="Top" ALIGN="Left">
<P>MUR
</TD>
<TD WIDTH="9%" VALIGN="Top" ALIGN="Left">
<P>DLW21SN670
<P>HQ2L
</TD>
<TD WIDTH="18%" VALIGN="Top" ALIGN="Left">
<P>L21,L22,L23
</TD>
<TD WIDTH="9%" VALIGN="Top" ALIGN="Left">
<P>?
</TD>
<TD WIDTH="9%" VALIGN="Top" ALIGN="Left">
<P>?
</TD>
<TD WIDTH="9%" VALIGN="Top" ALIGN="Left">
<P>?
</TD>
</TR>
<TR>
<TD WIDTH="5%" VALIGN="Top" ALIGN="Right">
<P>160
</TD>
<TD WIDTH="9%" VALIGN="Top" ALIGN="Left">
<P>CX220TN100
<P>1
</TD>
<TD WIDTH="9%" VALIGN="Top" ALIGN="Left">
<P>EMI 
<P>FILTER 
<P>BLM18SN220
<P>TN1D(22,
<P>8000MA)
</TD>
<TD WIDTH="9%" VALIGN="Top" ALIGN="Left">
<P>IND
</TD>
<TD WIDTH="3%" VALIGN="Top" ALIGN="Right">
<P>4
</TD>
<TD WIDTH="9%" VALIGN="Top" ALIGN="Left">
<P>?
</TD>
<TD WIDTH="9%" VALIGN="Top" ALIGN="Left">
<P>?
</TD>
<TD WIDTH="18%" VALIGN="Top" ALIGN="Left">
<P>PL4,PL19,PL29,PL32
</TD>
<TD WIDTH="9%" VALIGN="Top" ALIGN="Left">
<P>?
</TD>
<TD WIDTH="9%" VALIGN="Top" ALIGN="Left">
<P>?
</TD>
<TD WIDTH="9%" VALIGN="Top" ALIGN="Left">
<P>?
</TD>
</TR>
<TR>
<TD WIDTH="5%" VALIGN="Top" ALIGN="Right">
<P>161
</TD>
<TD WIDTH="9%" VALIGN="Top" ALIGN="Left">
<P>CX470T0500
<P>0
</TD>
<TD WIDTH="9%" VALIGN="Top" ALIGN="Left">
<P>EMI 
<P>FILTER 
<P>FCM1608KF-
<P>470T05(47,
<P>0.5A)
</TD>
<TD WIDTH="9%" VALIGN="Top" ALIGN="Left">
<P>IND
</TD>
<TD WIDTH="3%" VALIGN="Top" ALIGN="Right">
<P>3
</TD>
<TD WIDTH="9%" VALIGN="Top" ALIGN="Left">
<P>?
</TD>
<TD WIDTH="9%" VALIGN="Top" ALIGN="Left">
<P>?
</TD>
<TD WIDTH="18%" VALIGN="Top" ALIGN="Left">
<P>L28,L29,L30
</TD>
<TD WIDTH="9%" VALIGN="Top" ALIGN="Left">
<P>?
</TD>
<TD WIDTH="9%" VALIGN="Top" ALIGN="Left">
<P>?
</TD>
<TD WIDTH="9%" VALIGN="Top" ALIGN="Left">
<P>?
</TD>
</TR>
<TR>
<TD WIDTH="5%" VALIGN="Top" ALIGN="Right">
<P>162
</TD>
<TD WIDTH="9%" VALIGN="Top" ALIGN="Left">
<P>CX8EG12100
<P>0
</TD>
<TD WIDTH="9%" VALIGN="Top" ALIGN="Left">
<P>EMI 
<P>FILTER 
<P>BLM18EG121
<P>SN1D(120.2
<P>A)
</TD>
<TD WIDTH="9%" VALIGN="Top" ALIGN="Left">
<P>IND
</TD>
<TD WIDTH="3%" VALIGN="Top" ALIGN="Right">
<P>2
</TD>
<TD WIDTH="9%" VALIGN="Top" ALIGN="Left">
<P>?
</TD>
<TD WIDTH="9%" VALIGN="Top" ALIGN="Left">
<P>?
</TD>
<TD WIDTH="18%" VALIGN="Top" ALIGN="Left">
<P>L17,L19
</TD>
<TD WIDTH="9%" VALIGN="Top" ALIGN="Left">
<P>?
</TD>
<TD WIDTH="9%" VALIGN="Top" ALIGN="Left">
<P>?
</TD>
<TD WIDTH="9%" VALIGN="Top" ALIGN="Left">
<P>?
</TD>
</TR>
<TR>
<TD WIDTH="5%" VALIGN="Top" ALIGN="Right">
<P>163
</TD>
<TD WIDTH="9%" VALIGN="Top" ALIGN="Left">
<P>CX8PG12100
<P>9
</TD>
<TD WIDTH="9%" VALIGN="Top" ALIGN="Left">
<P>EMI 
<P>FILTER 
<P>BLM18PG121
<P>SN(120,
<P>2000MA)
</TD>
<TD WIDTH="9%" VALIGN="Top" ALIGN="Left">
<P>IND
</TD>
<TD WIDTH="3%" VALIGN="Top" ALIGN="Right">
<P>14
</TD>
<TD WIDTH="9%" VALIGN="Top" ALIGN="Left">
<P>?
</TD>
<TD WIDTH="9%" VALIGN="Top" ALIGN="Left">
<P>?
</TD>
<TD WIDTH="18%" VALIGN="Top" ALIGN="Left">
<P>L2,L3,L4,L5,L6,L7,
<P>L8,L10,L11,L12,L13,
<P>L14,L15,L16
</TD>
<TD WIDTH="9%" VALIGN="Top" ALIGN="Left">
<P>?
</TD>
<TD WIDTH="9%" VALIGN="Top" ALIGN="Left">
<P>?
</TD>
<TD WIDTH="9%" VALIGN="Top" ALIGN="Left">
<P>?
</TD>
</TR>
<TR>
<TD WIDTH="5%" VALIGN="Top" ALIGN="Right">
<P>164
</TD>
<TD WIDTH="9%" VALIGN="Top" ALIGN="Left">
<P>CX8PG12100
<P>9
</TD>
<TD WIDTH="9%" VALIGN="Top" ALIGN="Left">
<P>EMI 
<P>FILTER 
<P>BLM18PG121
<P>SN(120,
<P>2000MA)
</TD>
<TD WIDTH="9%" VALIGN="Top" ALIGN="Left">
<P>EMPTY
</TD>
<TD WIDTH="3%" VALIGN="Top" ALIGN="Right">
<P>1
</TD>
<TD WIDTH="9%" VALIGN="Top" ALIGN="Left">
<P>?
</TD>
<TD WIDTH="9%" VALIGN="Top" ALIGN="Left">
<P>?
</TD>
<TD WIDTH="18%" VALIGN="Top" ALIGN="Left">
<P>L9
</TD>
<TD WIDTH="9%" VALIGN="Top" ALIGN="Left">
<P>?
</TD>
<TD WIDTH="9%" VALIGN="Top" ALIGN="Left">
<P>?
</TD>
<TD WIDTH="9%" VALIGN="Top" ALIGN="Left">
<P>?
</TD>
</TR>
<TR>
<TD WIDTH="5%" VALIGN="Top" ALIGN="Right">
<P>165
</TD>
<TD WIDTH="9%" VALIGN="Top" ALIGN="Left">
<P>DFHD03MS25
<P>1
</TD>
<TD WIDTH="9%" VALIGN="Top" ALIGN="Left">
<P>CONN SMD 
<P>HEADER 3P 
<P>1R 
<P>MS(P2.54, 
<P>H9.3)
</TD>
<TD WIDTH="9%" VALIGN="Top" ALIGN="Left">
<P>EMPTY
</TD>
<TD WIDTH="3%" VALIGN="Top" ALIGN="Right">
<P>1
</TD>
<TD WIDTH="9%" VALIGN="Top" ALIGN="Left">
<P>PRX
</TD>
<TD WIDTH="9%" VALIGN="Top" ALIGN="Left">
<P>212-91-035
<P>BR2
</TD>
<TD WIDTH="18%" VALIGN="Top" ALIGN="Left">
<P>J6
</TD>
<TD WIDTH="9%" VALIGN="Top" ALIGN="Left">
<P>?
</TD>
<TD WIDTH="9%" VALIGN="Top" ALIGN="Left">
<P>?
</TD>
<TD WIDTH="9%" VALIGN="Top" ALIGN="Left">
<P>?
</TD>
</TR>
<TR>
<TD WIDTH="5%" VALIGN="Top" ALIGN="Right">
<P>166
</TD>
<TD WIDTH="9%" VALIGN="Top" ALIGN="Left">
<P>DFHD08MS39
<P>2
</TD>
<TD WIDTH="9%" VALIGN="Top" ALIGN="Left">
<P>CONN DIP 
<P>HEADER 8P 
<P>1R 
<P>MS(P2.54,
<P>H8.6)
</TD>
<TD WIDTH="9%" VALIGN="Top" ALIGN="Left">
<P>IO
</TD>
<TD WIDTH="3%" VALIGN="Top" ALIGN="Right">
<P>1
</TD>
<TD WIDTH="9%" VALIGN="Top" ALIGN="Left">
<P>PRX
</TD>
<TD WIDTH="9%" VALIGN="Top" ALIGN="Left">
<P>210-HP1-08
<P>0BR1
</TD>
<TD WIDTH="18%" VALIGN="Top" ALIGN="Left">
<P>J7
</TD>
<TD WIDTH="9%" VALIGN="Top" ALIGN="Left">
<P>?
</TD>
<TD WIDTH="9%" VALIGN="Top" ALIGN="Left">
<P>?
</TD>
<TD WIDTH="9%" VALIGN="Top" ALIGN="Left">
<P>?
</TD>
</TR>
<TR>
<TD WIDTH="5%" VALIGN="Top" ALIGN="Right">
<P>167
</TD>
<TD WIDTH="9%" VALIGN="Top" ALIGN="Left">
<P>DFHD13MS08
<P>0
</TD>
<TD WIDTH="9%" VALIGN="Top" ALIGN="Left">
<P>CONN SMD 
<P>HEADER 
<P>13P 1R 
<P>MS(P1.0,
<P>H4.3)
</TD>
<TD WIDTH="9%" VALIGN="Top" ALIGN="Left">
<P>IO
</TD>
<TD WIDTH="3%" VALIGN="Top" ALIGN="Right">
<P>1
</TD>
<TD WIDTH="9%" VALIGN="Top" ALIGN="Left">
<P>ACS
</TD>
<TD WIDTH="9%" VALIGN="Top" ALIGN="Left">
<P>50228-0130
<P>C-V01
</TD>
<TD WIDTH="18%" VALIGN="Top" ALIGN="Left">
<P>J8
</TD>
<TD WIDTH="9%" VALIGN="Top" ALIGN="Left">
<P>?
</TD>
<TD WIDTH="9%" VALIGN="Top" ALIGN="Left">
<P>?
</TD>
<TD WIDTH="9%" VALIGN="Top" ALIGN="Left">
<P>?
</TD>
</TR>
<TR>
<TD WIDTH="5%" VALIGN="Top" ALIGN="Right">
<P>168
</TD>
<TD WIDTH="9%" VALIGN="Top" ALIGN="Left">
<P>DFHS09FR40
<P>1
</TD>
<TD WIDTH="9%" VALIGN="Top" ALIGN="Left">
<P>CONN DIP 
<P>USB3.0 9P 
<P>2R 
<P>FR(P2.0,
<P>H7.74)
</TD>
<TD WIDTH="9%" VALIGN="Top" ALIGN="Left">
<P>IO
</TD>
<TD WIDTH="3%" VALIGN="Top" ALIGN="Right">
<P>1
</TD>
<TD WIDTH="9%" VALIGN="Top" ALIGN="Left">
<P>APL
</TD>
<TD WIDTH="9%" VALIGN="Top" ALIGN="Left">
<P>GSB311131H
<P>R
</TD>
<TD WIDTH="18%" VALIGN="Top" ALIGN="Left">
<P>J2
</TD>
<TD WIDTH="9%" VALIGN="Top" ALIGN="Left">
<P>?
</TD>
<TD WIDTH="9%" VALIGN="Top" ALIGN="Left">
<P>?
</TD>
<TD WIDTH="9%" VALIGN="Top" ALIGN="Left">
<P>?
</TD>
</TR>
<TR>
<TD WIDTH="5%" VALIGN="Top" ALIGN="Right">
<P>169
</TD>
<TD WIDTH="9%" VALIGN="Top" ALIGN="Left">
<P>DFHS11FS00
<P>9
</TD>
<TD WIDTH="9%" VALIGN="Top" ALIGN="Left">
<P>CONN SMD 
<P>HOUSING 
<P>11P 2R 
<P>FS(P1,
<P>H3.28)
</TD>
<TD WIDTH="9%" VALIGN="Top" ALIGN="Left">
<P>IO
</TD>
<TD WIDTH="3%" VALIGN="Top" ALIGN="Right">
<P>2
</TD>
<TD WIDTH="9%" VALIGN="Top" ALIGN="Left">
<P>BER
</TD>
<TD WIDTH="9%" VALIGN="Top" ALIGN="Left">
<P>91920-3111
<P>1LF
</TD>
<TD WIDTH="18%" VALIGN="Top" ALIGN="Left">
<P>J5,J10
</TD>
<TD WIDTH="9%" VALIGN="Top" ALIGN="Left">
<P>?
</TD>
<TD WIDTH="9%" VALIGN="Top" ALIGN="Left">
<P>?
</TD>
<TD WIDTH="9%" VALIGN="Top" ALIGN="Left">
<P>?
</TD>
</TR>
<TR>
<TD WIDTH="5%" VALIGN="Top" ALIGN="Right">
<P>170
</TD>
<TD WIDTH="9%" VALIGN="Top" ALIGN="Left">
<P>DFHS20FR23
<P>3
</TD>
<TD WIDTH="9%" VALIGN="Top" ALIGN="Left">
<P>CONN SMD 
<P>HOUSING 
<P>20P 4R 
<P>FR(P0.6,
<P>H5.9)
</TD>
<TD WIDTH="9%" VALIGN="Top" ALIGN="Left">
<P>IO
</TD>
<TD WIDTH="3%" VALIGN="Top" ALIGN="Right">
<P>1
</TD>
<TD WIDTH="9%" VALIGN="Top" ALIGN="Left">
<P>FOX
</TD>
<TD WIDTH="9%" VALIGN="Top" ALIGN="Left">
<P>3VM11207-D
<P>730-7H
</TD>
<TD WIDTH="18%" VALIGN="Top" ALIGN="Left">
<P>J3
</TD>
<TD WIDTH="9%" VALIGN="Top" ALIGN="Left">
<P>?
</TD>
<TD WIDTH="9%" VALIGN="Top" ALIGN="Left">
<P>?
</TD>
<TD WIDTH="9%" VALIGN="Top" ALIGN="Left">
<P>?
</TD>
</TR>
<TR>
<TD WIDTH="5%" VALIGN="Top" ALIGN="Right">
<P>171
</TD>
<TD WIDTH="9%" VALIGN="Top" ALIGN="Left">
<P>DG01600000
<P>6
</TD>
<TD WIDTH="9%" VALIGN="Top" ALIGN="Left">
<P>IC SOCKET 
<P>SMD 
<P>16P(SPI,
<P>SOIC)(P1.2
<P>7,H5.8)
</TD>
<TD WIDTH="9%" VALIGN="Top" ALIGN="Left">
<P>IO
</TD>
<TD WIDTH="3%" VALIGN="Top" ALIGN="Right">
<P>1
</TD>
<TD WIDTH="9%" VALIGN="Top" ALIGN="Left">
<P>LTS
</TD>
<TD WIDTH="9%" VALIGN="Top" ALIGN="Left">
<P>ACA-SPI-00
<P>6-P06
</TD>
<TD WIDTH="18%" VALIGN="Top" ALIGN="Left">
<P>J40
</TD>
<TD WIDTH="9%" VALIGN="Top" ALIGN="Left">
<P>?
</TD>
<TD WIDTH="9%" VALIGN="Top" ALIGN="Left">
<P>?
</TD>
<TD WIDTH="9%" VALIGN="Top" ALIGN="Left">
<P>?
</TD>
</TR>
<TR>
<TD WIDTH="5%" VALIGN="Top" ALIGN="Right">
<P>172
</TD>
<TD WIDTH="9%" VALIGN="Top" ALIGN="Left">
<P>DHP00002F0
<P>0
</TD>
<TD WIDTH="9%" VALIGN="Top" ALIGN="Left">
<P>SWITCH 
<P>SMD PUSH 
<P>BUTTON 
<P>DHNF-02F-T
<P>-V-T/R
</TD>
<TD WIDTH="9%" VALIGN="Top" ALIGN="Left">
<P>MECH
</TD>
<TD WIDTH="3%" VALIGN="Top" ALIGN="Right">
<P>3
</TD>
<TD WIDTH="9%" VALIGN="Top" ALIGN="Left">
<P>DIP
</TD>
<TD WIDTH="9%" VALIGN="Top" ALIGN="Left">
<P>DHNF-02F-T
<P>-V-T/R
</TD>
<TD WIDTH="18%" VALIGN="Top" ALIGN="Left">
<P>SW1,SW2,SW3
</TD>
<TD WIDTH="9%" VALIGN="Top" ALIGN="Left">
<P>?
</TD>
<TD WIDTH="9%" VALIGN="Top" ALIGN="Left">
<P>?
</TD>
<TD WIDTH="9%" VALIGN="Top" ALIGN="Left">
<P>?
</TD>
</TR>
<TR>
<TD WIDTH="5%" VALIGN="Top" ALIGN="Right">
<P>173
</TD>
<TD WIDTH="9%" VALIGN="Top" ALIGN="Left">
<P>DHPDTSAM60
<P>4
</TD>
<TD WIDTH="9%" VALIGN="Top" ALIGN="Left">
<P>SWITCH 
<P>SMD 
<P>TACT(DTSAM
<P>-65NKSQR)
</TD>
<TD WIDTH="9%" VALIGN="Top" ALIGN="Left">
<P>MECH
</TD>
<TD WIDTH="3%" VALIGN="Top" ALIGN="Right">
<P>1
</TD>
<TD WIDTH="9%" VALIGN="Top" ALIGN="Left">
<P>DIP
</TD>
<TD WIDTH="9%" VALIGN="Top" ALIGN="Left">
<P>DTSAM-65NK
<P>SQR
</TD>
<TD WIDTH="18%" VALIGN="Top" ALIGN="Left">
<P>SW6
</TD>
<TD WIDTH="9%" VALIGN="Top" ALIGN="Left">
<P>?
</TD>
<TD WIDTH="9%" VALIGN="Top" ALIGN="Left">
<P>?
</TD>
<TD WIDTH="9%" VALIGN="Top" ALIGN="Left">
<P>?
</TD>
</TR>
<TR>
<TD WIDTH="5%" VALIGN="Top" ALIGN="Right">
<P>174
</TD>
<TD WIDTH="9%" VALIGN="Top" ALIGN="Left">
<P>DHPDTSAM60
<P>5
</TD>
<TD WIDTH="9%" VALIGN="Top" ALIGN="Left">
<P>SWITCH 
<P>SMD 
<P>TACT(DTSAM
<P>-65RSQR)
</TD>
<TD WIDTH="9%" VALIGN="Top" ALIGN="Left">
<P>MECH
</TD>
<TD WIDTH="3%" VALIGN="Top" ALIGN="Right">
<P>1
</TD>
<TD WIDTH="9%" VALIGN="Top" ALIGN="Left">
<P>DIP
</TD>
<TD WIDTH="9%" VALIGN="Top" ALIGN="Left">
<P>DTSAM-65RS
<P>QR
</TD>
<TD WIDTH="18%" VALIGN="Top" ALIGN="Left">
<P>SW7
</TD>
<TD WIDTH="9%" VALIGN="Top" ALIGN="Left">
<P>?
</TD>
<TD WIDTH="9%" VALIGN="Top" ALIGN="Left">
<P>?
</TD>
<TD WIDTH="9%" VALIGN="Top" ALIGN="Left">
<P>?
</TD>
</TR>
<TR>
<TD WIDTH="5%" VALIGN="Top" ALIGN="Right">
<P>175
</TD>
<TD WIDTH="9%" VALIGN="Top" ALIGN="Left">
<P>DK050TPU01
<P>1
</TD>
<TD WIDTH="9%" VALIGN="Top" ALIGN="Left">
<P>FUSE SMD 
<P>0.5A,
<P>6V(POLY,
<P>1206L050YR
<P>)
</TD>
<TD WIDTH="9%" VALIGN="Top" ALIGN="Left">
<P>IC
</TD>
<TD WIDTH="3%" VALIGN="Top" ALIGN="Right">
<P>1
</TD>
<TD WIDTH="9%" VALIGN="Top" ALIGN="Left">
<P>?
</TD>
<TD WIDTH="9%" VALIGN="Top" ALIGN="Left">
<P>?
</TD>
<TD WIDTH="18%" VALIGN="Top" ALIGN="Left">
<P>L1
</TD>
<TD WIDTH="9%" VALIGN="Top" ALIGN="Left">
<P>?
</TD>
<TD WIDTH="9%" VALIGN="Top" ALIGN="Left">
<P>?
</TD>
<TD WIDTH="9%" VALIGN="Top" ALIGN="Left">
<P>?
</TD>
</TR>
<TR>
<TD WIDTH="5%" VALIGN="Top" ALIGN="Right">
<P>176
</TD>
<TD WIDTH="9%" VALIGN="Top" ALIGN="Left">
<P>DK110TPU00
<P>3
</TD>
<TD WIDTH="9%" VALIGN="Top" ALIGN="Left">
<P>FUSE SMD 
<P>1.1A 8V 
<P>POLY(SMD12
<P>06P110TFT)
</TD>
<TD WIDTH="9%" VALIGN="Top" ALIGN="Left">
<P>IC
</TD>
<TD WIDTH="3%" VALIGN="Top" ALIGN="Right">
<P>1
</TD>
<TD WIDTH="9%" VALIGN="Top" ALIGN="Left">
<P>?
</TD>
<TD WIDTH="9%" VALIGN="Top" ALIGN="Left">
<P>?
</TD>
<TD WIDTH="18%" VALIGN="Top" ALIGN="Left">
<P>FS1
</TD>
<TD WIDTH="9%" VALIGN="Top" ALIGN="Left">
<P>?
</TD>
<TD WIDTH="9%" VALIGN="Top" ALIGN="Left">
<P>?
</TD>
<TD WIDTH="9%" VALIGN="Top" ALIGN="Left">
<P>?
</TD>
</TR>
<TR>
<TD WIDTH="5%" VALIGN="Top" ALIGN="Right">
<P>177
</TD>
<TD WIDTH="9%" VALIGN="Top" ALIGN="Left">
<P>DUMMY1
</TD>
<TD WIDTH="9%" VALIGN="Top" ALIGN="Left">
<P>QUANTA_LOG
<P>O_7X26
</TD>
<TD WIDTH="9%" VALIGN="Top" ALIGN="Left">
<P>EMPTY
</TD>
<TD WIDTH="3%" VALIGN="Top" ALIGN="Right">
<P>1
</TD>
<TD WIDTH="9%" VALIGN="Top" ALIGN="Left">
<P>?
</TD>
<TD WIDTH="9%" VALIGN="Top" ALIGN="Left">
<P>?
</TD>
<TD WIDTH="18%" VALIGN="Top" ALIGN="Left">
<P>ME1
</TD>
<TD WIDTH="9%" VALIGN="Top" ALIGN="Left">
<P>?
</TD>
<TD WIDTH="9%" VALIGN="Top" ALIGN="Left">
<P>?
</TD>
<TD WIDTH="9%" VALIGN="Top" ALIGN="Left">
<P>?
</TD>
</TR>
<TR>
<TD WIDTH="5%" VALIGN="Top" ALIGN="Right">
<P>178
</TD>
<TD WIDTH="9%" VALIGN="Top" ALIGN="Left">
<P>DUMMY2
</TD>
<TD WIDTH="9%" VALIGN="Top" ALIGN="Left">
<P>WEEE
</TD>
<TD WIDTH="9%" VALIGN="Top" ALIGN="Left">
<P>EMPTY
</TD>
<TD WIDTH="3%" VALIGN="Top" ALIGN="Right">
<P>1
</TD>
<TD WIDTH="9%" VALIGN="Top" ALIGN="Left">
<P>?
</TD>
<TD WIDTH="9%" VALIGN="Top" ALIGN="Left">
<P>?
</TD>
<TD WIDTH="18%" VALIGN="Top" ALIGN="Left">
<P>ME2
</TD>
<TD WIDTH="9%" VALIGN="Top" ALIGN="Left">
<P>?
</TD>
<TD WIDTH="9%" VALIGN="Top" ALIGN="Left">
<P>?
</TD>
<TD WIDTH="9%" VALIGN="Top" ALIGN="Left">
<P>?
</TD>
</TR>
<TR>
<TD WIDTH="5%" VALIGN="Top" ALIGN="Right">
<P>179
</TD>
<TD WIDTH="9%" VALIGN="Top" ALIGN="Left">
<P>DUMMY3
</TD>
<TD WIDTH="9%" VALIGN="Top" ALIGN="Left">
<P>PB-E1_SMAL
<P>L
</TD>
<TD WIDTH="9%" VALIGN="Top" ALIGN="Left">
<P>EMPTY
</TD>
<TD WIDTH="3%" VALIGN="Top" ALIGN="Right">
<P>1
</TD>
<TD WIDTH="9%" VALIGN="Top" ALIGN="Left">
<P>?
</TD>
<TD WIDTH="9%" VALIGN="Top" ALIGN="Left">
<P>?
</TD>
<TD WIDTH="18%" VALIGN="Top" ALIGN="Left">
<P>DM7
</TD>
<TD WIDTH="9%" VALIGN="Top" ALIGN="Left">
<P>?
</TD>
<TD WIDTH="9%" VALIGN="Top" ALIGN="Left">
<P>?
</TD>
<TD WIDTH="9%" VALIGN="Top" ALIGN="Left">
<P>?
</TD>
</TR>
<TR>
<TD WIDTH="5%" VALIGN="Top" ALIGN="Right">
<P>180
</TD>
<TD WIDTH="9%" VALIGN="Top" ALIGN="Left">
<P>DUMMY50
</TD>
<TD WIDTH="9%" VALIGN="Top" ALIGN="Left">
<P>HOLE_TOOLI
<P>NGD125N_T2
<P>-0
</TD>
<TD WIDTH="9%" VALIGN="Top" ALIGN="Left">
<P>EMPTY
</TD>
<TD WIDTH="3%" VALIGN="Top" ALIGN="Right">
<P>2
</TD>
<TD WIDTH="9%" VALIGN="Top" ALIGN="Left">
<P>?
</TD>
<TD WIDTH="9%" VALIGN="Top" ALIGN="Left">
<P>?
</TD>
<TD WIDTH="18%" VALIGN="Top" ALIGN="Left">
<P>H2B1,H2B2
</TD>
<TD WIDTH="9%" VALIGN="Top" ALIGN="Left">
<P>?
</TD>
<TD WIDTH="9%" VALIGN="Top" ALIGN="Left">
<P>?
</TD>
<TD WIDTH="9%" VALIGN="Top" ALIGN="Left">
<P>?
</TD>
</TR>
<TR>
<TD WIDTH="5%" VALIGN="Top" ALIGN="Right">
<P>181
</TD>
<TD WIDTH="9%" VALIGN="Top" ALIGN="Left">
<P>DUMMY8
</TD>
<TD WIDTH="9%" VALIGN="Top" ALIGN="Left">
<P>BMC_FLASH
</TD>
<TD WIDTH="9%" VALIGN="Top" ALIGN="Left">
<P>MECH
</TD>
<TD WIDTH="3%" VALIGN="Top" ALIGN="Right">
<P>2
</TD>
<TD WIDTH="9%" VALIGN="Top" ALIGN="Left">
<P>?
</TD>
<TD WIDTH="9%" VALIGN="Top" ALIGN="Left">
<P>?
</TD>
<TD WIDTH="18%" VALIGN="Top" ALIGN="Left">
<P>DM2,DM5
</TD>
<TD WIDTH="9%" VALIGN="Top" ALIGN="Left">
<P>?
</TD>
<TD WIDTH="9%" VALIGN="Top" ALIGN="Left">
<P>?
</TD>
<TD WIDTH="9%" VALIGN="Top" ALIGN="Left">
<P>?
</TD>
</TR>
<TR>
<TD WIDTH="5%" VALIGN="Top" ALIGN="Right">
<P>182
</TD>
<TD WIDTH="9%" VALIGN="Top" ALIGN="Left">
<P>GOLD244
</TD>
<TD WIDTH="9%" VALIGN="Top" ALIGN="Left">
<P>GOLD_168P_
<P>ME10168102
<P>02011_SCM
</TD>
<TD WIDTH="9%" VALIGN="Top" ALIGN="Left">
<P>EMPTY
</TD>
<TD WIDTH="3%" VALIGN="Top" ALIGN="Right">
<P>1
</TD>
<TD WIDTH="9%" VALIGN="Top" ALIGN="Left">
<P>APL
</TD>
<TD WIDTH="9%" VALIGN="Top" ALIGN="Left">
<P>?
</TD>
<TD WIDTH="18%" VALIGN="Top" ALIGN="Left">
<P>GF1
</TD>
<TD WIDTH="9%" VALIGN="Top" ALIGN="Left">
<P>?
</TD>
<TD WIDTH="9%" VALIGN="Top" ALIGN="Left">
<P>?
</TD>
<TD WIDTH="9%" VALIGN="Top" ALIGN="Left">
<P>?
</TD>
</TR>
<TR>
<TD WIDTH="5%" VALIGN="Top" ALIGN="Right">
<P>183
</TD>
<TD WIDTH="9%" VALIGN="Top" ALIGN="Left">
<P>HOLE1101
</TD>
<TD WIDTH="9%" VALIGN="Top" ALIGN="Left">
<P>HOLE_C5-5D
<P>3-2B7_NPB
</TD>
<TD WIDTH="9%" VALIGN="Top" ALIGN="Left">
<P>EMPTY
</TD>
<TD WIDTH="3%" VALIGN="Top" ALIGN="Right">
<P>2
</TD>
<TD WIDTH="9%" VALIGN="Top" ALIGN="Left">
<P>?
</TD>
<TD WIDTH="9%" VALIGN="Top" ALIGN="Left">
<P>?
</TD>
<TD WIDTH="18%" VALIGN="Top" ALIGN="Left">
<P>H6,H7
</TD>
<TD WIDTH="9%" VALIGN="Top" ALIGN="Left">
<P>?
</TD>
<TD WIDTH="9%" VALIGN="Top" ALIGN="Left">
<P>?
</TD>
<TD WIDTH="9%" VALIGN="Top" ALIGN="Left">
<P>?
</TD>
</TR>
<TR>
<TD WIDTH="5%" VALIGN="Top" ALIGN="Right">
<P>184
</TD>
<TD WIDTH="9%" VALIGN="Top" ALIGN="Left">
<P>HOLE1211
</TD>
<TD WIDTH="9%" VALIGN="Top" ALIGN="Left">
<P>HOLE_C6-03
<P>D3-13B6-03
<P>_NPB
</TD>
<TD WIDTH="9%" VALIGN="Top" ALIGN="Left">
<P>EMPTY
</TD>
<TD WIDTH="3%" VALIGN="Top" ALIGN="Right">
<P>2
</TD>
<TD WIDTH="9%" VALIGN="Top" ALIGN="Left">
<P>?
</TD>
<TD WIDTH="9%" VALIGN="Top" ALIGN="Left">
<P>?
</TD>
<TD WIDTH="18%" VALIGN="Top" ALIGN="Left">
<P>H5,H9
</TD>
<TD WIDTH="9%" VALIGN="Top" ALIGN="Left">
<P>?
</TD>
<TD WIDTH="9%" VALIGN="Top" ALIGN="Left">
<P>?
</TD>
<TD WIDTH="9%" VALIGN="Top" ALIGN="Left">
<P>?
</TD>
</TR>
<TR>
<TD WIDTH="5%" VALIGN="Top" ALIGN="Right">
<P>185
</TD>
<TD WIDTH="9%" VALIGN="Top" ALIGN="Left">
<P>HOLE620
</TD>
<TD WIDTH="9%" VALIGN="Top" ALIGN="Left">
<P>HOLE_C6D3-
<P>4B6_NPB
</TD>
<TD WIDTH="9%" VALIGN="Top" ALIGN="Left">
<P>EMPTY
</TD>
<TD WIDTH="3%" VALIGN="Top" ALIGN="Right">
<P>2
</TD>
<TD WIDTH="9%" VALIGN="Top" ALIGN="Left">
<P>?
</TD>
<TD WIDTH="9%" VALIGN="Top" ALIGN="Left">
<P>?
</TD>
<TD WIDTH="18%" VALIGN="Top" ALIGN="Left">
<P>H3,H4
</TD>
<TD WIDTH="9%" VALIGN="Top" ALIGN="Left">
<P>?
</TD>
<TD WIDTH="9%" VALIGN="Top" ALIGN="Left">
<P>?
</TD>
<TD WIDTH="9%" VALIGN="Top" ALIGN="Left">
<P>?
</TD>
</TR>
<TR>
<TD WIDTH="5%" VALIGN="Top" ALIGN="Right">
<P>186
</TD>
<TD WIDTH="9%" VALIGN="Top" ALIGN="Left">
<P>N_A
</TD>
<TD WIDTH="9%" VALIGN="Top" ALIGN="Left">
<P>(USE 
<P>SYM_2)TDR 
<P>3PIN,
<P>2X141MIL 
<P>1X100MIL 
<P>P2P
</TD>
<TD WIDTH="9%" VALIGN="Top" ALIGN="Left">
<P>EMPTY
</TD>
<TD WIDTH="3%" VALIGN="Top" ALIGN="Right">
<P>6
</TD>
<TD WIDTH="9%" VALIGN="Top" ALIGN="Left">
<P>?
</TD>
<TD WIDTH="9%" VALIGN="Top" ALIGN="Left">
<P>?
</TD>
<TD WIDTH="18%" VALIGN="Top" ALIGN="Left">
<P>DB1,DB2,DB3,DB4,DB5,
<P>DB6
</TD>
<TD WIDTH="9%" VALIGN="Top" ALIGN="Left">
<P>?
</TD>
<TD WIDTH="9%" VALIGN="Top" ALIGN="Left">
<P>?
</TD>
<TD WIDTH="9%" VALIGN="Top" ALIGN="Left">
<P>?
</TD>
</TR>
<TR>
<TD WIDTH="5%" VALIGN="Top" ALIGN="Right">
<P>187
</TD>
<TD WIDTH="9%" VALIGN="Top" ALIGN="Left">
<P>N_A
</TD>
<TD WIDTH="9%" VALIGN="Top" ALIGN="Left">
<P>DIFF_TEST_
<P>PAD DIP 
<P>FOR FTS 
<P>ONLY
</TD>
<TD WIDTH="9%" VALIGN="Top" ALIGN="Left">
<P>EMPTY
</TD>
<TD WIDTH="3%" VALIGN="Top" ALIGN="Right">
<P>16
</TD>
<TD WIDTH="9%" VALIGN="Top" ALIGN="Left">
<P>?
</TD>
<TD WIDTH="9%" VALIGN="Top" ALIGN="Left">
<P>?
</TD>
<TD WIDTH="18%" VALIGN="Top" ALIGN="Left">
<P>X1,X2,X5,X6,X7,X8,
<P>X11,X12,X13,X14,X17,
<P>X18,X19,X20,X23,X24
</TD>
<TD WIDTH="9%" VALIGN="Top" ALIGN="Left">
<P>?
</TD>
<TD WIDTH="9%" VALIGN="Top" ALIGN="Left">
<P>?
</TD>
<TD WIDTH="9%" VALIGN="Top" ALIGN="Left">
<P>?
</TD>
</TR>
<TR>
<TD WIDTH="5%" VALIGN="Top" ALIGN="Right">
<P>188
</TD>
<TD WIDTH="9%" VALIGN="Top" ALIGN="Left">
<P>TMP_QAL009
<P>555K04
</TD>
<TD WIDTH="9%" VALIGN="Top" ALIGN="Left">
<P>IC(24P) 
<P>PCA9555PW(
<P>TSSOP)EP
</TD>
<TD WIDTH="9%" VALIGN="Top" ALIGN="Left">
<P>IC
</TD>
<TD WIDTH="3%" VALIGN="Top" ALIGN="Right">
<P>1
</TD>
<TD WIDTH="9%" VALIGN="Top" ALIGN="Left">
<P>?
</TD>
<TD WIDTH="9%" VALIGN="Top" ALIGN="Left">
<P>?
</TD>
<TD WIDTH="18%" VALIGN="Top" ALIGN="Left">
<P>U40
</TD>
<TD WIDTH="9%" VALIGN="Top" ALIGN="Left">
<P>?
</TD>
<TD WIDTH="9%" VALIGN="Top" ALIGN="Left">
<P>?
</TD>
<TD WIDTH="9%" VALIGN="Top" ALIGN="Left">
<P>?
</TD>
</TR>
<TR>
<TD WIDTH="5%" VALIGN="Top" ALIGN="Right">
<P>189
</TD>
<TD WIDTH="9%" VALIGN="Top" ALIGN="Left">
<P>TP24
</TD>
<TD WIDTH="9%" VALIGN="Top" ALIGN="Left">
<P>Probe for 
<P>DELTA-L 
<P>measuremen
<P>t
</TD>
<TD WIDTH="9%" VALIGN="Top" ALIGN="Left">
<P>EMPTY
</TD>
<TD WIDTH="3%" VALIGN="Top" ALIGN="Right">
<P>16
</TD>
<TD WIDTH="9%" VALIGN="Top" ALIGN="Left">
<P>?
</TD>
<TD WIDTH="9%" VALIGN="Top" ALIGN="Left">
<P>?
</TD>
<TD WIDTH="18%" VALIGN="Top" ALIGN="Left">
<P>J9,J11,J12,J16,J17,
<P>J19,J20,J22,J23,J24,
<P>J25,J26,J27,J28,J29,
<P>J30
</TD>
<TD WIDTH="9%" VALIGN="Top" ALIGN="Left">
<P>?
</TD>
<TD WIDTH="9%" VALIGN="Top" ALIGN="Left">
<P>?
</TD>
<TD WIDTH="9%" VALIGN="Top" ALIGN="Left">
<P>?
</TD>
</TR>
<TR>
<TD WIDTH="5%" VALIGN="Top" ALIGN="Right">
<B><P>TOTAL</B>
</TD>
<TD WIDTH="9%" VALIGN="Top" ALIGN="Left">
<P>-
</TD>
<TD WIDTH="9%" VALIGN="Top" ALIGN="Left">
<P>-
</TD>
<TD WIDTH="9%" VALIGN="Top" ALIGN="Left">
<P>-
</TD>
<TD WIDTH="3%" VALIGN="Top" ALIGN="Right">
<P>1405
</TD>
<TD WIDTH="9%" VALIGN="Top" ALIGN="Left">
<P>-
</TD>
<TD WIDTH="9%" VALIGN="Top" ALIGN="Left">
<P>-
</TD>
<TD WIDTH="18%" VALIGN="Top" ALIGN="Left">
<P>-
</TD>
<TD WIDTH="9%" VALIGN="Top" ALIGN="Left">
<P>-
</TD>
<TD WIDTH="9%" VALIGN="Top" ALIGN="Left">
<P>-
</TD>
<TD WIDTH="9%" VALIGN="Top" ALIGN="Left">
<P>-
</TD>
</TR>
</TABLE>
</BODY>
</HTML>